G04 ================== begin FILE IDENTIFICATION RECORD ==================*
G04 Layout Name:  13948-1b.brd*
G04 Film Name:    L6*
G04 File Format:  Gerber RS274X*
G04 File Origin:  Cadence Allegro 16.5-S045*
G04 Origin Date:  Thu Nov 13 15:46:17 2014*
G04 *
G04 Layer:  VIA CLASS/L6*
G04 Layer:  PIN/L6*
G04 Layer:  ETCH/L6*
G04 Layer:  DRAWING FORMAT/LAYER_PCB_STORY*
G04 Layer:  DRAWING FORMAT/LAYER_L6*
G04 *
G04 Offset:    (0.00 0.00)*
G04 Mirror:    No*
G04 Mode:      Positive*
G04 Rotation:  0*
G04 FullContactRelief:  No*
G04 UndefLineWidth:     6.00*
G04 ================== end FILE IDENTIFICATION RECORD ====================*
%FSLAX35Y35*MOIN*%
%IR0*IPPOS*OFA0.00000B0.00000*MIA0B0*SFA1.00000B1.00000*%
%ADD13C,.02*%
%ADD12C,.022*%
%ADD19C,.05*%
%ADD16C,.043*%
%ADD15C,.061*%
%ADD18C,.054*%
%ADD14C,.046*%
%ADD10C,.028*%
%ADD20C,.056*%
%ADD17C,.078*%
%ADD11C,.115*%
%ADD21C,.01*%
%ADD22C,.04*%
%ADD23C,.025*%
%ADD24C,.004*%
%ADD25C,.005*%
%ADD26C,.006*%
%ADD27C,.0035*%
%ADD41C,.03004*%
%ADD47C,.03204*%
%ADD39C,.07004*%
%ADD38C,.05204*%
%ADD50C,.08004*%
%ADD48C,.06204*%
%ADD36C,.04404*%
%ADD43C,.09004*%
%ADD42C,.03604*%
%ADD35C,.04604*%
%ADD33C,.06404*%
%ADD49C,.05604*%
%ADD37C,.07404*%
%ADD30C,.08504*%
%ADD29C,.08604*%
%ADD46C,.07804*%
%ADD40C,.06904*%
%ADD28O,.21302X.15002*%
%ADD44C,.10204*%
%ADD45C,.13104*%
%ADD32C,.15004*%
%ADD31C,.15204*%
%ADD34C,.13904*%
G75*
%LPD*%
G75*
G36*
G01X297500Y3000D02*
X296500Y4000D01*
Y65500D01*
X292000Y70000D01*
X248500D01*
X247000Y71500D01*
Y228500D01*
X243500Y232000D01*
X226959D01*
G02X226657Y232662I0J400D01*
G03X221373I-2642J2299D01*
G02X221071Y232000I-302J-262D01*
G01X115000D01*
X111500Y235500D01*
Y304500D01*
X105500Y310500D01*
X12501D01*
X3001Y320000D01*
Y967001D01*
X3500Y967500D01*
Y970000D01*
X18500Y985000D01*
X107000D01*
X112000Y990000D01*
X116254D01*
G03X119746I1746J1500D01*
G01X134000D01*
X136500Y987500D01*
X186000D01*
X188500Y985000D01*
X264000D01*
X269500Y990500D01*
Y996500D01*
X273000Y1000000D01*
X539500D01*
X541500Y998000D01*
Y991000D01*
X545500Y987000D01*
X552500D01*
X556500Y991000D01*
Y998000D01*
X559000Y1000500D01*
X590500D01*
X594000Y997000D01*
Y988500D01*
X597500Y985000D01*
X716500D01*
X720500Y989000D01*
Y998000D01*
X722000Y999500D01*
X740000D01*
X742000Y997500D01*
Y991500D01*
X746500Y987000D01*
X795000D01*
X797000Y985000D01*
X901500D01*
X918500Y968000D01*
Y772000D01*
X922000Y768500D01*
X988000D01*
X992000Y772500D01*
Y967500D01*
X1009500Y985000D01*
X1381000D01*
X1396500Y969500D01*
Y702000D01*
X1394500Y700000D01*
X1387000D01*
X1329000Y758000D01*
Y843500D01*
X1313500Y859000D01*
X1242502D01*
X1165402Y936100D01*
Y936102D01*
X1165002Y936502D01*
Y958814D01*
X1165402Y959214D01*
Y962034D01*
X1163409Y964026D01*
X1160591D01*
X1160141Y963576D01*
X1083344D01*
X1067048Y947281D01*
Y946548D01*
X1067000Y946500D01*
Y848000D01*
X1046345Y827345D01*
X1046204Y827467D01*
G03X1042550Y827223I-1704J-1967D01*
G02X1041950I-300J264D01*
G03X1041723Y827450I-1950J-1723D01*
G02Y828050I264J300D01*
G03X1038050Y831723I-1723J1950D01*
G02X1037450I-300J264D01*
G03X1033777Y828050I-1950J-1723D01*
G02Y827450I-264J-300D01*
G03X1037450Y823777I1723J-1950D01*
G02X1038050I300J-264D01*
G03X1042089Y823949I1950J1723D01*
G02X1042411I161J-119D01*
G03X1042533Y823796I2094J1545D01*
G01X1042655Y823655D01*
X1042452Y823452D01*
X1042450D01*
X995548Y776550D01*
Y772301D01*
X983605Y760358D01*
X915319D01*
X833760Y841917D01*
Y867171D01*
X828969Y871962D01*
X826538D01*
X826500Y872000D01*
X816053D01*
X775000Y913053D01*
Y915336D01*
G03Y918664I-2000J1664D01*
G01Y919836D01*
G03Y923164I-2000J1664D01*
G01Y925336D01*
G03Y928664I-2000J1664D01*
G01Y933801D01*
X775202Y934002D01*
Y969998D01*
X775000Y970199D01*
Y971000D01*
X772500Y973500D01*
X752172D01*
G02X751777Y973959I0J400D01*
G03X747223I-2277J341D01*
G02X746828Y973500I-395J-59D01*
G01X364795D01*
G03X363681Y973825I-1181J-1976D01*
G02X363294Y974192I12J400D01*
G03X358700Y973915I-2294J-192D01*
G02X358300Y973500I-400J-15D01*
G01X159000D01*
X150000Y964500D01*
Y933500D01*
X154500Y929000D01*
X368927D01*
G03X369496Y928257I2074J999D01*
G02X369511Y927665I-261J-303D01*
G03X372604Y927743I1589J-1665D01*
G02X372589Y928335I261J303D01*
G03X373073Y929000I-1589J1665D01*
G01X374532D01*
G02X374897Y928437I0J-400D01*
G03X379103I2103J-937D01*
G02X379468Y929000I365J163D01*
G01X382300D01*
G02X382552Y928289I0J-400D01*
G03X385448I1448J-1789D01*
G02X385700Y929000I252J311D01*
G01X433000D01*
X440000Y922000D01*
X759000D01*
X815500Y865500D01*
X820947D01*
X821899Y864548D01*
X826430D01*
X827548Y863430D01*
Y839777D01*
X829000Y838325D01*
Y837500D01*
X913500Y753000D01*
X914300D01*
G02X914700Y752585I0J-400D01*
G03X917646Y750290I2300J-85D01*
G01X917673Y750298D01*
X999275D01*
X1015778Y733795D01*
Y720278D01*
X1010000Y714500D01*
X962500D01*
X949000Y701000D01*
Y474000D01*
X968705Y454295D01*
G03X968803Y454197I1676J1578D01*
G01X968805Y454195D01*
X972000Y451000D01*
X1094000D01*
X1126500Y418500D01*
Y374970D01*
X1115030Y363500D01*
X967635D01*
G02X967245Y363989I0J400D01*
G03X962755I-2245J511D01*
G02X962365Y363500I-390J-89D01*
G01X906570D01*
X903100Y366970D01*
X856370D01*
X840900Y351500D01*
X823739D01*
G02X823348Y351986I0J400D01*
G03X818852I-2248J494D01*
G02X818461Y351500I-391J-86D01*
G01X804320D01*
X799100Y346280D01*
X766100D01*
X762740Y349640D01*
Y349680D01*
X760920Y351500D01*
X751626D01*
G02X751235Y351983I0J400D01*
G03X736559I-7338J1560D01*
G02X736168Y351500I-391J-83D01*
G01X663500D01*
X660000Y355000D01*
Y365942D01*
X660150Y365981D01*
G03X661884Y367457I-649J2520D01*
G02X662616I366J-161D01*
G03Y369543I2384J1043D01*
G02X661884I-366J161D01*
G03X660150Y371019I-2383J-1044D01*
G01X660000Y371058D01*
Y433838D01*
G02X660415Y434238I400J0D01*
G03Y438838I85J2300D01*
G02X660000Y439238I-15J400D01*
G01Y444594D01*
X660202Y444795D01*
Y466239D01*
X666489Y472527D01*
G02X667170Y472282I283J-283D01*
G03X671705Y471983I2292J218D01*
G02X672230Y472270I390J-89D01*
G03X674535Y472711I780J2166D01*
G02X675199Y472425I264J-300D01*
G03X675975Y474225I2301J75D01*
G02X675311Y474511I-264J300D01*
G03X670767Y474953I-2301J-75D01*
G02X670242Y474666I-390J89D01*
G03X669699Y474790I-780J-2166D01*
G02X669343Y475234I41J398D01*
G03X664761Y475679I-2287J266D01*
G01X664755Y475606D01*
X656798Y467649D01*
Y463167D01*
G02X656116Y462884I-400J0D01*
G01X656000Y463000D01*
X628303D01*
G02X628063Y463720I0J400D01*
G03X628359Y467620I-1563J2080D01*
G02Y468180I286J280D01*
G03X624641I-1859J1820D01*
G02Y467620I-286J-280D01*
G03X624937Y463720I1859J-1820D01*
G02X624697Y463000I-240J-320D01*
G01X621803D01*
G02X621563Y463720I0J400D01*
G03X621859Y467620I-1563J2080D01*
G02Y468180I286J280D01*
G03X618141I-1859J1820D01*
G02Y467620I-286J-280D01*
G03X618437Y463720I1859J-1820D01*
G02X618197Y463000I-240J-320D01*
G01X615303D01*
G02X615063Y463720I0J400D01*
G03X615359Y467620I-1563J2080D01*
G02Y468180I286J280D01*
G03X611173Y471164I-1859J1821D01*
G02X610440Y471204I-358J179D01*
G03X605579Y471253I-2440J-904D01*
G02X604846Y471226I-372J146D01*
G03X600641Y468280I-2346J-1126D01*
G02Y467720I-286J-280D01*
G03X601060Y463733I1859J-1820D01*
G02X600838Y463000I-222J-333D01*
G01X596500D01*
X594000Y465500D01*
Y582500D01*
X455500Y721000D01*
X389500D01*
X386000Y717500D01*
Y682000D01*
X381500Y677500D01*
X188000D01*
X171500Y661000D01*
X168468D01*
G02X168103Y661563I0J400D01*
G03X163897I-2103J937D01*
G02X163532Y661000I-365J-163D01*
G01X160315D01*
G02X159935Y661526I0J400D01*
G03X155565I-2185J724D01*
G02X155185Y661000I-380J-126D01*
G01X84500D01*
X26000Y602500D01*
Y491500D01*
X116000Y401500D01*
Y353000D01*
X124500Y344500D01*
X148500D01*
X161500Y331500D01*
Y327500D01*
X163500Y325500D01*
X187500D01*
X189500Y327500D01*
X195000D01*
X197000Y325500D01*
X197565D01*
Y325200D01*
X197485Y325140D01*
G03X200502Y321680I1378J-1844D01*
G02X201072I285J-281D01*
G03X204424Y324833I1638J1617D01*
G02X204722Y325500I298J267D01*
G01X206326D01*
G02X206624Y324833I0J-400D01*
G03X209955Y321659I1714J-1536D01*
G02X210517I281J-285D01*
G03X213848Y324833I1617J1638D01*
G02X214146Y325500I298J267D01*
G01X299500D01*
X355000Y270000D01*
X367000D01*
X369500Y267500D01*
Y260500D01*
X324500Y215500D01*
Y159900D01*
X330078Y154322D01*
G02X330057Y153737I-283J-283D01*
G03X329597Y152183I983J-1136D01*
G01X329606Y152153D01*
X329522Y149127D01*
X329512Y149097D01*
G03X332371Y149019I1417J-497D01*
G01X332363Y149049D01*
X332418Y151028D01*
G02X333100Y151300I400J-11D01*
G01X339000Y145400D01*
Y141000D01*
X337500Y139500D01*
X329102D01*
G02X328702Y139891I0J400D01*
G03X325498I-1602J-34D01*
G02X325098Y139500I-400J9D01*
G01X305500D01*
X302525Y142475D01*
G02X302666Y142816I141J141D01*
G01X303145D01*
X303176Y142806D01*
G03Y145850I501J1522D01*
G01X303145Y145840D01*
X301567D01*
G03X298805Y146388I-1735J-1512D01*
G01X298676Y146324D01*
X297702Y147298D01*
Y150002D01*
X300702Y153002D01*
Y231502D01*
X322202Y253002D01*
Y259998D01*
X320498Y261702D01*
X319799D01*
X319500Y262000D01*
X291500D01*
X255500Y226000D01*
Y203500D01*
X270500Y188500D01*
Y163018D01*
G02X270099Y162618I-400J0D01*
G03Y147616I-21J-7501D01*
G02X270500Y147216I1J-400D01*
G01Y100026D01*
G02X270099Y99626I-400J0D01*
G03X273073Y85247I-21J-7501D01*
G01X273198Y85302D01*
X280000Y78500D01*
X296000D01*
X306500Y68000D01*
Y33500D01*
X309000Y31000D01*
X317500D01*
X319000Y32500D01*
Y57000D01*
X320500Y58500D01*
X366000D01*
X367298Y59798D01*
X367495D01*
X370194Y62498D01*
X376011D01*
X379974Y66460D01*
X499344D01*
X499383Y66500D01*
X501500D01*
X575448Y140448D01*
X688215D01*
X694065Y146298D01*
X802812D01*
X803013Y146500D01*
X804500D01*
X831000Y173000D01*
X968000D01*
X977000Y182000D01*
Y193364D01*
G03Y195236I-1993J936D01*
G01Y225500D01*
X981500Y230000D01*
X1048000D01*
X1050434Y227566D01*
X1050445Y227506D01*
G03X1052506Y225445I2555J494D01*
G01X1052566Y225434D01*
X1054213Y223787D01*
X1054228Y223739D01*
G03X1055955Y222012I2488J761D01*
G01X1056003Y221997D01*
X1056571Y221429D01*
X1056319Y221177D01*
X1056185Y221257D01*
G03X1054025Y217199I-1185J-1973D01*
G02X1054031Y216477I-170J-362D01*
G03X1055760Y212433I969J-1977D01*
G02X1056298Y212058I138J-375D01*
G01Y211705D01*
X1054798Y210205D01*
Y195551D01*
G03X1056131Y191728I1702J-1551D01*
G01X1056298Y191701D01*
Y189798D01*
X1055103Y188603D01*
G02X1054476Y188680I-284J282D01*
G03X1051320Y185524I-1976J-1180D01*
G02X1051397Y184897I-205J-343D01*
G01X1030973Y164473D01*
G02X1030292Y164718I-283J283D01*
G03X1027782Y162208I-2292J-218D01*
G02X1028027Y161527I-38J-398D01*
G01X1023697Y157197D01*
X1023586Y157226D01*
G03X1020774Y154414I-586J-2226D01*
G01X1020803Y154303D01*
X973500Y107000D01*
X898000D01*
X890500Y99500D01*
Y77000D01*
X896000Y71500D01*
X1006500D01*
X1069602Y134602D01*
G02X1070198Y134568I283J-283D01*
G03X1073432Y137802I1802J1432D01*
G02X1073398Y138398I249J313D01*
G01X1084500Y149500D01*
Y184707D01*
G02X1085047Y185079I400J0D01*
G03X1087440Y189667I952J2421D01*
G02Y190333I222J333D01*
G03X1085047Y194921I-1441J2167D01*
G02X1084500Y195293I-147J372D01*
G01Y198000D01*
X1088500Y202000D01*
X1106500D01*
X1109000Y199500D01*
Y5000D01*
X1107000Y3000D01*
X297500D01*
G37*
G36*
G01X154500Y931500D02*
X153000Y933000D01*
Y965000D01*
X160000Y972000D01*
X359860D01*
G03X360933Y971699I1140J2000D01*
G02X361320Y971332I-12J-400D01*
G03X365915Y971589I2294J192D01*
G02X366315Y972000I400J11D01*
G01X665079D01*
G02X665363Y971319I0J-400D01*
G03X668637I1637J-1619D01*
G02X668921Y972000I284J281D01*
G01X731079D01*
G02X731363Y971319I0J-400D01*
G03X734637I1637J-1619D01*
G02X734921Y972000I284J281D01*
G01X749408D01*
G03X749592I92J2300D01*
G01X771500D01*
X774000Y969500D01*
Y934500D01*
X771000Y931500D01*
X436053D01*
X434291Y933261D01*
X434297Y933352D01*
G03X430145Y932137I-2297J148D01*
G02X429823Y931500I-322J-237D01*
G01X372746D01*
G03X370673Y932279I-1746J-1500D01*
G02X370229Y932575I-57J396D01*
G03X369685Y933568I-2229J-575D01*
G02X369907Y934234I293J272D01*
G03X367815Y934932I-406J2266D01*
G02X367593Y934266I-293J-272D01*
G03X365715Y931724I407J-2266D01*
G01X365716Y931712D01*
Y931500D01*
X365309D01*
X365295Y931684D01*
G03X361296Y933048I-2295J-184D01*
G02X360704I-296J269D01*
G03X356705Y931684I-1704J-1548D01*
G01X356691Y931500D01*
X154500D01*
G37*
G36*
G01X276250Y111500D02*
X272750Y115000D01*
Y148108D01*
G03Y162126I-2672J7009D01*
G01Y189250D01*
X257500Y204500D01*
Y224500D01*
X293500Y260500D01*
X320000D01*
X321000Y259500D01*
Y253500D01*
X299500Y232000D01*
Y153500D01*
X296500Y150500D01*
Y144000D01*
X302500Y138000D01*
X325588D01*
Y136826D01*
X325578Y136795D01*
G03X328622I1522J-501D01*
G01X328612Y136826D01*
Y138000D01*
X341000D01*
X347299Y131701D01*
G02X347298Y131135I-283J-283D01*
G03X349905Y129378I1131J-1135D01*
G01X349957Y129500D01*
X352019D01*
G02X352401Y128980I0J-400D01*
G03X352328Y128451I1528J-480D01*
G02X351828Y128051I-400J-12D01*
G03X353030Y126549I-399J-1551D01*
G02X353530Y126949I400J12D01*
G03X355457Y128980I399J1551D01*
G02X355839Y129500I382J120D01*
G01X363231D01*
G02X363631Y129107I0J-400D01*
G03X366635I1502J26D01*
G02X367035Y129500I400J-7D01*
G01X371000D01*
X376000Y134500D01*
Y135661D01*
X376013Y135694D01*
G03Y136748I-1407J527D01*
G01X376000Y136781D01*
Y138060D01*
G02X376684Y138342I400J0D01*
G03X378994Y138558I1066J1058D01*
G02X379660Y138552I331J-224D01*
G03X380072Y138130I1260J818D01*
G02X380070Y137468I-225J-330D01*
G03X381754Y137460I836J-1248D01*
G02X381756Y138122I225J330D01*
G03X382144Y138499I-836J1248D01*
G02X382796Y138500I326J-231D01*
G03X385266Y138533I1224J871D01*
G02X385929Y138534I332J-223D01*
G03X388428Y138551I1244J842D01*
G02X389097Y138550I334J-220D01*
G03X389513Y138127I1258J821D01*
G02X389512Y137465I-225J-331D01*
G03X391196I842J-1244D01*
G02X391197Y138127I225J331D01*
G03X391593Y138520I-842J1244D01*
G02X392256Y138513I329J-227D01*
G03X394769Y138520I1254J827D01*
G02X395436Y138525I335J-218D01*
G03X397931Y138526I1247J837D01*
G02X398594Y138529I333J-222D01*
G03X398966Y138150I1241J846D01*
G02X398955Y137490I-232J-326D01*
G03X400652Y137462I828J-1253D01*
G02X400663Y138122I232J326D01*
G03X401065Y138513I-828J1253D01*
G02X401720Y138512I327J-230D01*
G03X404197Y138528I1233J858D01*
G02X404859Y138529I331J-224D01*
G03X406946Y140614I1244J842D01*
G02Y141277I224J331D01*
G03X406954Y143758I-843J1243D01*
G02X406955Y144418I226J330D01*
G03X406961Y146897I-845J1242D01*
G02X406965Y147559I227J330D01*
G03X405274Y147567I-840J1245D01*
G02X405270Y146905I-227J-330D01*
G03X404866Y146502I839J-1246D01*
G02X404203Y146505I-330J225D01*
G03X401710Y146512I-1249J-835D01*
G02X401048I-331J224D01*
G03X398561Y146513I-1244J-842D01*
G02X397898I-332J224D01*
G03X395411Y146512I-1243J-843D01*
G02X394749I-331J224D01*
G03X392261I-1244J-842D01*
G02X391599I-331J224D01*
G03X389112Y146513I-1244J-842D01*
G02X388449I-332J224D01*
G03X385962Y146512I-1243J-843D01*
G02X385300I-331J224D01*
G03X383214Y144426I-1244J-842D01*
G02Y143764I-224J-331D01*
G03X382813Y143363I842J-1243D01*
G02X382150I-332J224D01*
G03X379663Y143362I-1243J-843D01*
G02X379001I-331J224D01*
G03X378599Y143764I-1244J-842D01*
G02Y144426I224J331D01*
G03X378615Y146903I-842J1244D01*
G02X378622Y147563I229J328D01*
G03X379008Y147937I-835J1248D01*
G02X379660Y147934I325J-233D01*
G03X379667Y149674I1228J865D01*
G02X379015Y149677I-325J233D01*
G03X378595Y150078I-1228J-865D01*
G02X378589Y150748I215J337D01*
G03X378606Y153241I-830J1252D01*
G02X378607Y153902I225J330D01*
G03X376502Y155958I-842J1244D01*
G02X375834Y155951I-336J217D01*
G03X375419Y156362I-1244J-841D01*
G02X375415Y157025I222J333D01*
G03X375424Y159502I-845J1242D01*
G02X375427Y160162I228J329D01*
G03X375824Y160559I-845J1242D01*
G02X376483Y160562I331J-225D01*
G03X378992Y160621I1235J855D01*
G02X379670I339J-212D01*
G03Y162213I1274J796D01*
G02X378992I-339J212D01*
G03X376476Y162262I-1274J-796D01*
G02X375817Y162259I-331J225D01*
G03X375419Y162651I-1235J-855D01*
G02X375418Y163315I223J332D01*
G03X373647Y165739I-841J1244D01*
G02X373000Y166053I-247J314D01*
G01Y175703D01*
G02X373644Y176020I400J0D01*
G03X375810Y176378I916J1190D01*
G02X376479Y176373I333J-222D01*
G03X378600Y178420I1262J815D01*
G02X378598Y179075I228J328D01*
G03X376872Y179070I-867J1227D01*
G02X376874Y178415I-228J-328D01*
G03X376491Y178020I869J-1225D01*
G02X375822Y178025I-333J222D01*
G03X373644Y178400I-1262J-815D01*
G02X373000Y178717I-244J317D01*
G01Y182000D01*
X370500Y184500D01*
X369404D01*
G03X367236I-1084J-1040D01*
G01X365000D01*
X363500Y186000D01*
Y206000D01*
X374169Y216669D01*
X374277Y216645D01*
G03X376072Y218440I330J1465D01*
G01X376048Y218548D01*
X385500Y228000D01*
X392865D01*
X392898Y227989D01*
G03X393960I531J1511D01*
G01X393993Y228000D01*
X397000D01*
X405500Y236500D01*
X421500D01*
X437000Y252000D01*
X440500D01*
X442500Y250000D01*
Y240000D01*
X435500Y233000D01*
Y230594D01*
G03X435200Y230200I1029J-1094D01*
G01X430500Y225500D01*
Y219359D01*
G03X430023Y218841I836J-1248D01*
G02X429331Y218828I-350J194D01*
G03X428861Y219311I-1284J-779D01*
G02X428887Y219999I217J336D01*
G03X427358Y220058I-715J1321D01*
G02X427332Y219370I-217J-336D01*
G03X426858Y218967I715J-1321D01*
G02X426213Y218983I-317J244D01*
G03X423739Y218974I-1234J-856D01*
G02X423081Y218970I-330J226D01*
G03X420615Y218964I-1231J-861D01*
G02X419959Y218962I-329J228D01*
G03X419560Y219351I-1230J-862D01*
G02Y220017I222J333D01*
G03X417898I-831J1251D01*
G02Y219351I-222J-333D01*
G03X417476Y218929I830J-1252D01*
G02X416808Y218931I-333J221D01*
G03X416804Y217280I-1257J-822D01*
G02X417472Y217278I333J-221D01*
G03X419964Y217245I1257J822D01*
G02X420620Y217247I329J-228D01*
G03X423090Y217262I1230J862D01*
G02X423748Y217266I330J-226D01*
G03X426168Y217209I1231J861D01*
G02X426813Y217193I317J-244D01*
G03X428484Y216612I1234J856D01*
G02X429000Y216229I116J-383D01*
G01Y215000D01*
X429170Y214830D01*
Y214329D01*
X430521Y212978D01*
X432709D01*
G02X433075Y212417I0J-400D01*
G03X435823I1374J-607D01*
G02X436189Y212978I366J161D01*
G01X438021D01*
X440000Y211000D01*
Y198000D01*
X438500Y196500D01*
Y196320D01*
X437818Y195637D01*
Y186757D01*
X438500Y186074D01*
Y182500D01*
X441750Y179250D01*
Y176750D01*
X441000Y176000D01*
X433041D01*
G02X432674Y176561I-1J400D01*
G03X430055Y178006I-1376J603D01*
G02X429393I-331J224D01*
G03X428408Y178644I-1244J-842D01*
G01X428346Y178654D01*
X426000Y181000D01*
Y191792D01*
G03X426243Y192070I-1001J1120D01*
G02X426905I331J-224D01*
G03Y193754I1244J842D01*
G02X426243I-331J224D01*
G03X424394Y194287I-1244J-842D01*
G01X424268Y194232D01*
X423000Y195500D01*
X387000D01*
X385574Y194074D01*
G02X385031Y194053I-283J283D01*
G03X384897Y194156I-981J-1137D01*
G02Y194818I224J331D01*
G03X383213I-842J1244D01*
G02Y194156I-224J-331D01*
G03X384880Y191657I841J-1245D01*
G02X385500Y191323I220J-334D01*
G01Y188202D01*
G02X384880Y187868I-400J0D01*
G03Y185358I-825J-1255D01*
G02X385500Y185024I220J-334D01*
G01Y178692D01*
G02X384875Y178362I-400J1D01*
G03X383170Y175889I-845J-1242D01*
G02Y175233I-229J-328D01*
G03X383173Y172771I862J-1230D01*
G02X383175Y172115I-228J-329D01*
G03X383216Y169633I866J-1227D01*
G02X383214Y168963I-219J-334D01*
G03X382806Y168570I819J-1259D01*
G02X382153I-327J231D01*
G03X379667Y168516I-1225J-869D01*
G02X378994Y168517I-336J217D01*
G03X378585Y168939I-1262J-814D01*
G02X378589Y169600I227J329D01*
G03X376897Y169610I-839J1246D01*
G02X376893Y168949I-227J-329D01*
G03X378993Y166888I839J-1246D01*
G02X379666Y166887I336J-217D01*
G03X382154Y166834I1262J814D01*
G02X382807I326J-231D01*
G03X385288Y166879I1225J869D01*
G02X385955Y166882I334J-219D01*
G03X386661Y166315I1250J833D01*
G01X386700Y166300D01*
X395237Y157763D01*
X395252Y157724D01*
G03X395810Y157023I1401J542D01*
G02Y156360I-224J-331D01*
G03X395792Y153886I843J-1243D01*
G02X395789Y153229I-229J-327D01*
G03X395407Y152849I851J-1238D01*
G02X394751I-328J229D01*
G03X392263Y152814I-1232J-859D01*
G02X391595I-334J220D01*
G03Y151166I-1256J-824D01*
G02X392263I334J-220D01*
G03X394751Y151131I1256J824D01*
G02X395407I328J-229D01*
G03X397884Y151150I1232J859D01*
G02X398553Y151142I332J-223D01*
G03X401051Y151090I1266J808D01*
G02X401706I328J-229D01*
G03Y152810I1232J860D01*
G02X401051I-327J229D01*
G03X398574Y152790I-1232J-860D01*
G02X397905Y152798I-332J223D01*
G03X397500Y153221I-1267J-807D01*
G02X397503Y153878I229J327D01*
G03X397223Y156506I-850J1238D01*
G02Y156877I76J186D01*
G03X397461Y157000I-568J1390D01*
G01X405295D01*
G03X405533Y156877I806J1268D01*
G02Y156507I-76J-185D01*
G03X406671I569J-1390D01*
G02Y156877I76J185D01*
G03X406909Y157000I-568J1391D01*
G01X411594D01*
G03X411831Y156877I808J1267D01*
G02Y156507I-76J-185D01*
G03X411560Y153874I571J-1389D01*
G02Y153211I-224J-331D01*
G03X411578Y150710I841J-1245D01*
G02X411581Y150043I-219J-334D01*
G03X413660Y147953I834J-1249D01*
G02X414319Y147958I331J-224D01*
G03X416794Y147975I1232J860D01*
G02X417457I332J-224D01*
G03X419944Y147976I1243J843D01*
G02X420606I331J-224D01*
G03X423093Y147975I1244J842D01*
G02X423756I331J-224D01*
G03X426243Y147976I1243J843D01*
G02X426905I331J-224D01*
G03Y149660I1244J842D01*
G02X426243I-331J224D01*
G03X423756Y149661I-1244J-842D01*
G02X423093I-332J224D01*
G03X420606Y149660I-1243J-843D01*
G02X419944I-331J224D01*
G03X417457Y149661I-1244J-842D01*
G02X416794I-331J224D01*
G03X416379Y150071I-1243J-843D01*
G02Y150738I221J334D01*
G03X414300Y152824I-830J1252D01*
G02X413638Y152819I-333J222D01*
G03X413243Y153211I-1237J-852D01*
G02Y153874I224J332D01*
G03X412972Y156508I-841J1244D01*
G02Y156878I76J185D01*
G03X413208Y157000I-569J1390D01*
G01X433257D01*
G02X433508Y156288I0J-400D01*
G03X435390I941J-1170D01*
G02X435641Y157000I251J312D01*
G01X438000D01*
X439000Y156000D01*
Y148500D01*
X435500Y145000D01*
Y138008D01*
G02X434963Y137633I-400J1D01*
G03X433267Y137147I-513J-1412D01*
G02X432627Y137160I-315J246D01*
G03X430092Y137011I-1220J-875D01*
G02X429400Y136997I-350J194D01*
G03X426886Y137080I-1284J-779D01*
G02X426231Y137081I-327J230D01*
G03X423757Y137063I-1231J-861D01*
G02X423095I-331J224D01*
G03X420608Y137064I-1244J-842D01*
G02X419945I-331J224D01*
G03X417458Y137063I-1243J-843D01*
G02X416796I-331J224D01*
G03X414316Y137074I-1244J-842D01*
G02X413659Y137072I-329J227D01*
G03X413665Y135357I-1230J-862D01*
G02X414322Y135359I329J-227D01*
G03X416796Y135379I1230J862D01*
G02X417458I331J-224D01*
G03X419945Y135378I1244J842D01*
G02X420608I332J-224D01*
G03X423094I1243J843D01*
G02X423756I331J-224D01*
G03X426230Y135358I1244J842D01*
G02X426885Y135357I327J-230D01*
G03X429431Y135492I1231J861D01*
G02X430123Y135506I350J-194D01*
G03X432590Y135359I1284J779D01*
G02X433230Y135346I315J-246D01*
G03X435200Y134920I1220J875D01*
G02X435500Y134746I100J-173D01*
G01Y134500D01*
X413000Y112000D01*
Y111500D01*
X354173D01*
G02X353838Y112120I-1J400D01*
G03X351162I-1338J880D01*
G02X350827Y111500I-334J-220D01*
G01X276250D01*
G37*
G36*
G01X423783Y108290D02*
X421500Y110573D01*
Y119791D01*
X436002Y134292D01*
Y134743D01*
G02X436653Y135054I400J0D01*
G03Y137388I946J1167D01*
G02X436002Y137699I-251J311D01*
G01Y141042D01*
G02X436653Y141353I400J0D01*
G03Y143687I946J1167D01*
G02X436002Y143998I-251J311D01*
G01Y144792D01*
X439502Y148292D01*
Y156208D01*
X438208Y157502D01*
X414268D01*
G02X413875Y157978I-1J400D01*
G03X410903Y158372I-1474J290D01*
G02X410504Y158000I-399J28D01*
G01X407999D01*
G02X407600Y158372I0J400D01*
G03X404604I-1498J-105D01*
G02X404205Y158000I-399J28D01*
G01X398550D01*
G02X398151Y158372I0J400D01*
G03X395764Y159476I-1498J-106D01*
G01X395625Y159375D01*
X388313Y166687D01*
X388415Y166825D01*
G03X388448Y166872I-1213J886D01*
G02X389111I332J-224D01*
G03Y168558I1243J843D01*
G02X388448I-332J224D01*
G03X386570Y169076I-1243J-843D01*
G02X386002Y169439I-168J363D01*
G01Y175440D01*
G02X386570Y175802I400J-1D01*
G03Y178526I634J1362D01*
G02X386002Y178888I-168J363D01*
G01Y193502D01*
X387000Y194500D01*
X395168D01*
G02X395480Y193850I0J-400D01*
G03X397826I1173J-938D01*
G02X398138Y194500I312J250D01*
G01X401467D01*
G02X401779Y193850I0J-400D01*
G03X404125I1173J-938D01*
G02X404437Y194500I312J250D01*
G01X407766D01*
G02X408078Y193850I0J-400D01*
G03X410424I1173J-938D01*
G02X410736Y194500I312J250D01*
G01X414066D01*
G02X414378Y193850I0J-400D01*
G03X416724I1173J-938D01*
G02X417036Y194500I312J250D01*
G01X420399D01*
G02X420709Y193848I0J-400D01*
G03X423112Y192048I1167J-946D01*
G02X423769Y192051I330J-227D01*
G03X424823Y191420I1231J860D01*
G01X425000Y191400D01*
Y179000D01*
X426655Y177345D01*
X426650Y177255D01*
G03X428240Y175665I1499J-91D01*
G01X428330Y175670D01*
X429000Y175000D01*
X432639D01*
G02X433020Y174477I0J-400D01*
G03X435692Y173172I1429J-462D01*
G02X436355I331J-224D01*
G03X439027Y174477I1243J843D01*
G02X439408Y175000I381J123D01*
G01X442092D01*
G02X442474Y174482I0J-400D01*
G03X445346I1436J-441D01*
G02X445728Y175000I382J118D01*
G01X453500D01*
X456097Y172403D01*
X456025Y172271D01*
G03X457348Y169900I1404J-771D01*
G02X457728Y169501I-20J-400D01*
G01Y155067D01*
X458000Y154794D01*
Y153035D01*
G03X458950Y150483I1069J-1055D01*
G01X459023Y150477D01*
X459520Y149980D01*
X459532Y149922D01*
G03X461221Y148233I2153J464D01*
G01X461279Y148221D01*
X461769Y147731D01*
X461767Y147647D01*
G03X464006Y145408I2202J-37D01*
G01X464090Y145410D01*
X464383Y145117D01*
X464357Y145008D01*
G03X467008Y142357I2143J-508D01*
G01X467117Y142383D01*
X468706Y140794D01*
X468714Y140725D01*
G03X470725Y138714I2286J275D01*
G01X470794Y138706D01*
X474500Y135000D01*
Y116500D01*
X474450Y116450D01*
Y109920D01*
X472820Y108290D01*
X459664D01*
X459654Y108291D01*
G03X459204I-225J-2291D01*
G01X459194Y108290D01*
X433241D01*
G02X432841Y108699I0J400D01*
G03X428239I-2301J51D01*
G02X427839Y108290I-400J-9D01*
G01X423783D01*
G37*
G36*
G01X487500Y360019D02*
Y359184D01*
X487335Y359155D01*
G03X486148Y357289I264J-1479D01*
G01X486177Y357177D01*
X484161Y355161D01*
X484049Y355190D01*
G03X482211Y353352I-387J-1451D01*
G01X482240Y353240D01*
X480224Y351224D01*
X480112Y351253D01*
G03X478819Y351000I-387J-1451D01*
G01X476694D01*
G03X474882I-906J-1198D01*
G01X472757D01*
G03X470945I-906J-1198D01*
G01X468820D01*
G03X467008I-906J-1198D01*
G01X464881D01*
G03X463009I-936J-1300D01*
G01X460946D01*
G03X459134I-906J-1198D01*
G01X456779D01*
G03X454871I-954J-1160D01*
G01X452053D01*
X450101Y352952D01*
X450089D01*
G02X449697Y353433I0J400D01*
G03X446757I-1470J306D01*
G02X446365Y352952I-392J-81D01*
G01X442215D01*
G02X441823Y353433I0J400D01*
G03X438883I-1470J306D01*
G02X438491Y352952I-392J-81D01*
G01X434601D01*
X433500Y354053D01*
Y360511D01*
G03Y362715I-1021J1102D01*
G01Y368385D01*
G03Y370589I-1021J1102D01*
G01Y376261D01*
G03Y378465I-1021J1102D01*
G01Y380198D01*
G03Y382402I-1021J1102D01*
G01Y384135D01*
G03Y386339I-1021J1102D01*
G01Y388072D01*
G03X432040Y390610I-1021J1102D01*
G01X431925Y390575D01*
X429982Y392518D01*
X430010Y392628D01*
G03X428183Y394455I-1455J372D01*
G01X428073Y394427D01*
X426500Y396000D01*
Y547500D01*
X431500Y552500D01*
X526000D01*
X527500Y551000D01*
Y521000D01*
X487500Y481000D01*
Y426115D01*
X487335Y426086D01*
G03Y423128I264J-1479D01*
G01X487500Y423099D01*
Y422178D01*
X487335Y422149D01*
G03Y419191I264J-1479D01*
G01X487500Y419162D01*
Y418241D01*
X487335Y418212D01*
G03Y415254I264J-1479D01*
G01X487500Y415225D01*
Y406430D01*
X487335Y406401D01*
G03Y403443I264J-1479D01*
G01X487500Y403414D01*
Y370991D01*
X487336Y370961D01*
G03Y368005I267J-1478D01*
G01X487500Y367975D01*
Y363027D01*
X487340Y362994D01*
G03Y360052I303J-1471D01*
G01X487500Y360019D01*
G37*
G36*
G01X444202Y316000D02*
Y318210D01*
X444436Y318445D01*
Y319436D01*
X445500Y320500D01*
Y329227D01*
G03Y331007I-1210J890D01*
G01Y332833D01*
G03Y335167I-945J1167D01*
G01Y337101D01*
G03X443177Y339000I-1209J891D01*
G01X441676D01*
G03X439490Y339059I-1121J-1000D01*
G01X439431Y339000D01*
X439000D01*
X438000Y340000D01*
Y347500D01*
X438500Y348000D01*
X449500D01*
X451000Y346500D01*
Y339069D01*
G03Y336931I1055J-1069D01*
G01Y334855D01*
G03Y333111I1223J-872D01*
G01Y322368D01*
X444632Y316000D01*
X444202D01*
G37*
G36*
G01X612000Y231000D02*
X665000Y178000D01*
X709673D01*
G03X713327I1827J1400D01*
G01X755079D01*
G03X756921I921J2000D01*
G01X770500D01*
X807500Y215000D01*
X971000D01*
X972500Y213500D01*
Y196500D01*
X969500Y193500D01*
X812500D01*
X786040Y167040D01*
X657960D01*
X605418Y219582D01*
X605405Y219605D01*
G03X604605Y220405I-1905J-1105D01*
G01X604582Y220418D01*
X602000Y223000D01*
Y229000D01*
X604000Y231000D01*
X612000D01*
G37*
G36*
G01X897000Y74000D02*
X892500Y78500D01*
Y99500D01*
X897500Y104500D01*
X974500D01*
X1022714Y152714D01*
X1022807Y152706D01*
G03X1025294Y155193I193J2294D01*
G01X1025286Y155286D01*
X1057500Y187500D01*
Y191927D01*
G03X1058202Y195551I-1000J2074D01*
G01Y205188D01*
G02X1058808Y205530I400J0D01*
G03X1061870Y208843I1192J1969D01*
G02X1062018Y209435I325J233D01*
G03X1062702Y213051I-1018J2065D01*
G01Y214275D01*
X1090725Y242298D01*
X1152205D01*
X1152406Y242500D01*
X1157500D01*
G02X1157899Y242087I-1J-400D01*
G03X1162450Y240277I2601J-87D01*
G02X1163050I300J-264D01*
G03X1167601Y242087I1950J1723D01*
G02X1168000Y242500I400J13D01*
G01X1184094D01*
X1184495Y242098D01*
X1190653D01*
X1201035Y252480D01*
X1236361D01*
G02X1236752Y251995I0J-400D01*
G03X1240976Y250320I2248J-494D01*
G02X1241603Y250397I343J-205D01*
G01X1256000Y236000D01*
Y206140D01*
G03Y203860I2000J-1140D01*
G01Y169000D01*
X1255632Y168632D01*
G03X1254368Y167368I868J-2132D01*
G01X1251500Y164500D01*
X1240500D01*
X1236500Y168500D01*
Y188800D01*
G02X1237211Y189052I400J0D01*
G03Y191948I1789J1448D01*
G02X1236500Y192200I-311J252D01*
G01Y219000D01*
X1233500Y222000D01*
X1209001D01*
G02X1208801Y222746I0J400D01*
G03X1206294Y227306I-1301J2254D01*
G02X1205734Y227519I-186J354D01*
G03X1201480Y228459I-2434J-919D01*
G02X1200920I-280J286D01*
G03X1197280I-1820J-1859D01*
G02X1196720I-280J286D01*
G03Y224741I-1820J-1859D01*
G02X1197280I280J-286D01*
G03X1200920I1820J1859D01*
G02X1201480I280J-286D01*
G03X1204506Y224294I1821J1859D01*
G02X1205066Y224081I186J-354D01*
G03X1206199Y222746I2435J918D01*
G02X1205999Y222000I-200J-346D01*
G01X1178609D01*
X1178595Y222186D01*
G03X1173833Y223440I-2595J-186D01*
G02X1173167I-333J222D01*
G03X1169050Y223723I-2167J-1440D01*
G02X1168450I-300J264D01*
G03X1164333Y223440I-1950J-1723D01*
G02X1163667I-333J222D01*
G03X1158905Y222186I-2167J-1440D01*
G01X1158891Y222000D01*
X1100000D01*
X1082999Y204999D01*
Y204245D01*
G03Y200755I1501J-1745D01*
G01Y192420D01*
G02X1082259Y192209I-400J0D01*
G03Y189791I-1959J-1209D01*
G02X1082999Y189580I340J-211D01*
G01Y159864D01*
G03X1082967Y156984I2151J-1464D01*
G01X1082999Y156935D01*
Y155881D01*
G03X1082780Y155579I1991J-1675D01*
G02X1082182Y155485I-340J212D01*
G03X1077934Y153068I-1682J-1985D01*
G02X1077534Y152602I-394J-66D01*
G03X1077442Y147399I-34J-2602D01*
G02X1077716Y146716I-9J-400D01*
G01X1035140Y104140D01*
G02X1034476Y104299I-283J282D01*
G03X1031201Y101024I-2476J-799D01*
G02X1031360Y100360I-123J-381D01*
G01X1019271Y88271D01*
G02X1018620Y88398I-283J283D01*
G03X1015602Y85380I-2120J-898D01*
G02X1015729Y84729I-156J-368D01*
G01X1005000Y74000D01*
X897000D01*
G37*
G36*
G01X1092500Y869500D02*
X1112483Y849517D01*
G02X1112432Y848909I-283J-282D01*
G03X1114903Y845031I1336J-1875D01*
G02X1115500Y844683I197J-348D01*
G01Y822500D01*
X1102000Y809000D01*
Y784500D01*
X1081000Y763500D01*
Y687500D01*
X1080000Y686500D01*
X1073500D01*
X1072500Y687500D01*
Y718000D01*
X1068500Y722000D01*
Y780000D01*
X1086000Y797500D01*
Y833214D01*
X1087102Y834316D01*
Y837134D01*
X1086000Y838236D01*
Y868500D01*
X1087000Y869500D01*
X1092500D01*
G37*
G36*
G01X1121000Y821500D02*
X1117000Y825500D01*
Y849500D01*
X1100216Y866284D01*
G02X1100369Y866945I283J283D01*
G03X1097445Y869869I-746J2178D01*
G02X1096784Y869716I-378J130D01*
G01X1084652Y881848D01*
Y954713D01*
G03X1085501Y956424I-1452J1787D01*
G01X1085503Y956503D01*
X1087000Y958000D01*
X1138500D01*
X1226000Y870500D01*
Y850000D01*
X1197500Y821500D01*
X1183902D01*
G03X1179550Y822223I-2402J-1000D01*
G02X1178950I-300J264D01*
G03X1174598Y821500I-1950J-1723D01*
G01X1131776D01*
G03X1128284I-1746J-1500D01*
G01X1121000D01*
G37*
G36*
G01X1140755Y675000D02*
X1140745Y675189D01*
G03X1138271Y676249I-1500J-83D01*
G02X1137729Y676271I-259J305D01*
G01X1137647Y676353D01*
X1137651Y676440D01*
G03X1136801Y677854I-1501J60D01*
G02X1136703Y678508I173J360D01*
G03X1136432Y680916I-1018J1105D01*
G02X1136412Y681598I199J347D01*
G03X1136437Y684094I-823J1256D01*
G02X1136429Y684748I226J330D01*
G03X1134333Y686846I-878J1219D01*
G02X1133679Y686854I-324J234D01*
G03X1131196Y686846I-1239J-850D01*
G02X1130533I-331J224D01*
G03X1130116Y687259I-1245J-840D01*
G02X1130112Y687924I220J334D01*
G03X1130132Y690402I-839J1246D01*
G02X1130135Y691061I228J328D01*
G03X1130524Y691446I-845J1242D01*
G02X1131186Y691438I328J-228D01*
G03X1133243Y693534I1254J827D01*
G02X1133239Y694208I214J338D01*
G03X1133659Y694615I-815J1262D01*
G02X1134325Y694604I329J-227D01*
G03X1134353Y696269I1264J811D01*
G02X1133687Y696280I-329J227D01*
G03X1133303Y696686I-1264J-811D01*
G02X1133306Y697337I234J324D01*
G03X1133282Y699808I-866J1227D01*
G02Y700470I224J331D01*
G03X1133245Y702982I-842J1244D01*
G02X1133237Y703653I214J338D01*
G03X1131148Y705725I-831J1251D01*
G02X1130482Y705720I-335J219D01*
G03X1130082Y706121I-1244J-841D01*
G02X1130092Y706789I225J331D01*
G03X1130122Y709303I-807J1267D01*
G02X1130120Y709967I222J333D01*
G03X1130118Y712454I-843J1243D01*
G02X1130114Y713115I224J332D01*
G03X1130516Y713527I-854J1235D01*
G02X1131186Y713526I335J-219D01*
G03X1131189Y715168I1259J819D01*
G02X1130519Y715169I-335J219D01*
G03X1128025Y715205I-1259J-819D01*
G02X1127365Y715209I-329J228D01*
G03X1125279Y713124I-1244J-841D01*
G02Y712462I-224J-331D01*
G03X1125316Y709950I842J-1244D01*
G02X1125323Y709279I-215J-338D01*
G03X1125292Y706800I832J-1250D01*
G02X1125279Y706136I-230J-328D01*
G03X1125272Y703616I814J-1262D01*
G02X1125276Y702950I-219J-334D01*
G03X1127363Y700869I838J-1247D01*
G02X1128027Y700871I333J-222D01*
G03X1128436Y700465I1243J843D01*
G02X1128440Y699802I-222J-333D01*
G03X1130534Y697722I850J-1238D01*
G02X1131196I331J-224D01*
G03X1131560Y697347I1243J843D01*
G02X1131557Y696696I-234J-324D01*
G03X1131620Y694200I866J-1227D01*
G02X1131624Y693526I-214J-338D01*
G03X1131206Y693122I815J-1262D01*
G02X1130544Y693130I-328J228D01*
G03X1128030Y693121I-1254J-827D01*
G02X1127363Y693116I-335J218D01*
G03X1126970Y693514I-1246J-838D01*
G02X1126979Y694178I228J329D01*
G03X1125303Y694200I-822J1257D01*
G02X1125294Y693536I-228J-329D01*
G03X1125252Y691050I822J-1257D01*
G02X1125254Y690397I-230J-327D01*
G03X1124812Y689906I868J-1226D01*
G02X1124181Y689819I-349J196D01*
G01X1099000Y715000D01*
Y732000D01*
X1087500Y743500D01*
Y768000D01*
X1089500Y770000D01*
X1110000D01*
X1113000Y767000D01*
Y740719D01*
G02X1112322Y740432I-400J0D01*
G03Y737268I-1532J-1582D01*
G02X1113000Y736981I278J-287D01*
G01Y732000D01*
X1120000Y725000D01*
X1137000D01*
X1139196Y722804D01*
G02X1138865Y722124I-283J-283D01*
G03X1137863Y719376I-180J-1491D01*
G02X1137872Y718713I-219J-335D01*
G03X1137870Y716248I858J-1233D01*
G02Y715592I-229J-328D01*
G03X1139952Y713487I860J-1232D01*
G02X1140606Y713483I326J-232D01*
G03X1141070Y713049I1235J855D01*
G02X1141055Y712353I-205J-344D01*
G03X1143084Y710311I710J-1323D01*
G02X1143764Y710347I351J-192D01*
G03X1146256Y710377I1236J853D01*
G02X1146923Y710381I335J-219D01*
G03X1149500Y711915I1246J839D01*
G02X1149855Y712500I355J185D01*
G01X1153000D01*
X1155000Y710500D01*
Y707000D01*
X1159500Y702500D01*
X1172000D01*
X1175000Y699500D01*
Y698698D01*
X1174999Y698690D01*
G03Y698438I1497J-126D01*
G01X1175000Y698430D01*
Y696843D01*
G02X1174340Y696539I-400J0D01*
G03X1172520Y694155I-976J-1142D01*
G02X1172524Y693497I-225J-330D01*
G03X1174344Y691110I860J-1232D01*
G02X1175000Y690803I256J-307D01*
G01Y687443D01*
G02X1174346Y687134I-400J0D01*
G03Y684814I-954J-1160D01*
G02X1175000Y684505I254J-309D01*
G01Y683085D01*
X1174998Y683070D01*
G03Y682610I1484J-230D01*
G01X1175000Y682595D01*
Y681000D01*
X1169637Y675637D01*
G02X1169005Y675726I-282J283D01*
G03X1166201Y675176I-1313J-730D01*
G01X1166180Y675000D01*
X1162294D01*
G02X1161973Y675639I0J400D01*
G03X1159563I-1205J896D01*
G02X1159242Y675000I-321J-239D01*
G01X1142119D01*
X1142087Y675011D01*
G03X1141113I-487J-1421D01*
G01X1141081Y675000D01*
X1140755D01*
G37*
G36*
G01X1183000Y705500D02*
X1181500Y707000D01*
Y712000D01*
X1182000Y712500D01*
X1185000D01*
X1192000Y719500D01*
Y742800D01*
G02X1192415Y743200I400J0D01*
G03X1194204Y743952I86J2300D01*
G02X1194796I296J-269D01*
G03X1196827Y743221I1704J1548D01*
G02X1197271Y742925I57J-396D01*
G03X1199173Y745779I2229J575D01*
G02X1198729Y746075I-57J396D01*
G03X1194796Y747048I-2229J-575D01*
G02X1194204I-296J269D01*
G03X1192415Y747800I-1703J-1548D01*
G02X1192000Y748200I-15J400D01*
G01Y751500D01*
X1200000Y759500D01*
X1200430D01*
Y759215D01*
X1200369Y759156D01*
G03X1203823Y758863I1599J-1656D01*
G02X1204145Y759500I322J237D01*
G01X1212500D01*
X1222500Y749500D01*
Y737000D01*
X1230500Y729000D01*
Y724500D01*
X1222000Y716000D01*
Y711614D01*
X1215886Y705500D01*
X1191512D01*
X1191492Y705676D01*
G03X1188508I-1492J-176D01*
G01X1188488Y705500D01*
X1183000D01*
G37*
G36*
G01X1211499Y3001D02*
X1210000Y4500D01*
Y137500D01*
X1212000Y139500D01*
X1249000D01*
X1252500Y136000D01*
Y20000D01*
X1256000Y16500D01*
X1387500D01*
X1392500Y21500D01*
Y34000D01*
X1385500Y41000D01*
Y101000D01*
X1387500Y103000D01*
X1395500D01*
X1396500Y102000D01*
Y99003D01*
G02X1395787Y98754I-400J0D01*
G03Y93766I-3130J-2494D01*
G02X1396500Y93517I313J-249D01*
G01Y81287D01*
G02X1395787Y81038I-400J0D01*
G03Y76050I-3130J-2494D01*
G02X1396500Y75801I313J-249D01*
G01Y62782D01*
G02X1395787Y62533I-400J0D01*
G03Y57545I-3130J-2494D01*
G02X1396500Y57296I313J-249D01*
G01Y45066D01*
G02X1395787Y44817I-400J0D01*
G03Y39829I-3130J-2494D01*
G02X1396500Y39580I313J-249D01*
G01Y4000D01*
X1395501Y3001D01*
X1211499D01*
G37*
G36*
G01X1341040Y79000D02*
X1334500Y85540D01*
Y268697D01*
G02X1335137Y269019I400J0D01*
G03X1338773Y271240I1363J1855D01*
G02X1339143Y271702I395J63D01*
G03X1336727Y273634I-143J2298D01*
G02X1336357Y273172I-395J-63D01*
G03X1335137Y272729I144J-2298D01*
G02X1334500Y273051I-237J322D01*
G01Y323500D01*
X1323603Y334397D01*
G02X1323680Y335024I282J284D01*
G03X1321137Y338855I-1180J1976D01*
G02X1320500Y339177I-237J322D01*
G01Y368778D01*
X1320507Y368804D01*
G03Y370196I-2507J696D01*
G01X1320500Y370222D01*
Y374778D01*
X1320507Y374804D01*
G03Y376196I-2507J696D01*
G01X1320500Y376222D01*
Y378500D01*
X1319872Y379128D01*
G02X1319868Y379689I283J283D01*
G03X1316189Y383368I-1868J1811D01*
G02X1315628Y383372I-278J287D01*
G01X1309750Y389250D01*
Y425750D01*
X1323000Y439000D01*
X1329360D01*
G03X1331596Y438976I1140J2000D01*
G01X1331641Y439000D01*
X1332500D01*
X1334500Y441000D01*
X1334603Y440983D01*
G03X1334915Y445550I397J2267D01*
G02X1334500Y445950I-15J400D01*
G01Y452000D01*
X1318000Y468500D01*
Y519698D01*
G02X1318554Y520067I400J0D01*
G03X1321601Y522149I846J2033D01*
G02X1322139Y522534I400J9D01*
G03X1320699Y524551I761J2066D01*
G02X1320161Y524166I-400J-9D01*
G03X1318554Y524133I-761J-2066D01*
G02X1318000Y524502I-154J369D01*
G01Y530915D01*
G02X1318446Y531313I400J1D01*
G03X1320100Y531801I254J2187D01*
G02X1320669Y531739I254J-309D01*
G03X1322692Y535283I1731J1361D01*
G02X1322462Y535962I53J396D01*
G01X1333500Y547000D01*
Y554365D01*
G02X1333989Y554755I400J0D01*
G03Y559245I511J2245D01*
G02X1333500Y559635I-89J390D01*
G01Y601000D01*
X1336500Y604000D01*
Y608548D01*
X1336502Y608550D01*
X1346263D01*
G03X1345564Y611454I1354J1862D01*
G01X1336500D01*
Y613460D01*
X1338540Y615500D01*
X1346000D01*
X1346049Y615548D01*
X1356481D01*
X1356514Y615536D01*
G03X1355171Y618575I786J2164D01*
G01X1355120Y618452D01*
X1347500D01*
Y624000D01*
X1349809Y626309D01*
X1349888Y626311D01*
G03X1351500Y630183I-71J2301D01*
G01Y633000D01*
X1355000Y636500D01*
X1361000D01*
X1363500Y634000D01*
Y630000D01*
X1363519Y629981D01*
G02X1363216Y629299I-283J-282D01*
G03X1364804Y625452I-116J-2299D01*
G02X1365500Y625183I296J-269D01*
G01Y602000D01*
X1375000Y592500D01*
Y573000D01*
X1394500Y553500D01*
Y124553D01*
X1393999Y124052D01*
X1391791D01*
G03Y121148I-1787J-1452D01*
G01X1394500D01*
Y112500D01*
X1390286Y108286D01*
X1390194Y108294D01*
G03X1387710Y105810I-190J-2294D01*
G01X1387718Y105718D01*
X1361000Y79000D01*
X1341040D01*
G37*
%LPC*%
G75*
G36*
G01X83756Y873235D02*
X90380Y866611D01*
Y848107D01*
G02X85476I-2452J0D01*
G01Y864581D01*
X78852Y871205D01*
Y884470D01*
G02X83756I2452J0D01*
G01Y873235D01*
G37*
G36*
G01X432070Y822498D02*
X426776Y827792D01*
Y868208D01*
X433570Y875002D01*
X479986D01*
X485280Y869708D01*
Y827792D01*
X479986Y822498D01*
X432070D01*
G37*
G36*
G01X408692Y985394D02*
G03X408766Y985986I-228J329D01*
G02X411623Y985491I1734J1514D01*
G03X411583Y985171I98J-175D01*
G02X411656Y985099I-1580J-1674D01*
G03X411944I144J139D01*
G02X412066Y981783I1656J-1599D01*
G03X411534I-266J-298D01*
G02X408692Y985394I-1533J1717D01*
G37*
G36*
G01X364577Y977428D02*
G03X364210Y977815I-400J-12D01*
G02X362822Y978429I185J2294D01*
G03X362175Y978280I-273J-292D01*
G02X361598Y980780I-2151J820D01*
G03X362245Y980929I273J292D01*
G02X366411Y981222I2151J-820D01*
G03X367122Y981243I350J193D01*
G02X371488Y980505I2078J-991D01*
G03X371977Y980160I397J44D01*
G02X370212Y977665I523J-2242D01*
G03X369723Y978010I-397J-44D01*
G02X369523Y977973I-518J2243D01*
G03X369179Y977565I56J-396D01*
G02X364577Y977428I-2301J-65D01*
G37*
G36*
G01X54125Y941335D02*
G03Y940680I230J-328D01*
G02X51483I-1321J-1885D01*
G03Y941335I-230J328D01*
G02X54125I1321J1885D01*
G37*
G36*
G01X131307Y932250D02*
G03X131678Y931769I392J-82D01*
G02X129358Y930161I-124J-2299D01*
G03X129158Y930420I-191J59D01*
G02X129035Y930418I-99J2300D01*
G03X128835Y930191I-2J-200D01*
G02X124435Y928982I-2281J-309D01*
G03X123701Y928989I-369J-156D01*
G02X119469Y929049I-2103J935D01*
G03X118729I-370J-152D01*
G02X114298Y929965I-2129J875D01*
G03X114095Y930168I-200J3D01*
G02X114044I-26J2302D01*
G03X113845Y929948I0J-200D01*
G02X109267Y929979I-2291J-228D01*
G03X108897Y930423I-397J45D01*
G02X111310Y932261I157J2297D01*
G03X111510Y932022I196J-39D01*
G02X111564I27J-2302D01*
G03X111763Y932242I0J200D01*
G02X116356Y932429I2291J228D01*
G03X116559Y932226I200J-3D01*
G01X116599D01*
G03X116798Y932433I-1J200D01*
G02X121229Y933390I2301J84D01*
G03X121969I370J152D01*
G02X126171Y933515I2129J-875D01*
G03X126905Y933545I361J174D01*
G02X131307Y932250I2148J-826D01*
G37*
G36*
G01X53140Y928313D02*
G03X52400I-370J-152D01*
G02X50201Y931487I-2130J873D01*
G03X50571Y932005I-12J400D01*
G02X54900Y933559I2199J681D01*
G03X55640I370J152D01*
G02X59900I2130J-873D01*
G03X60640I370J152D01*
G02X62839Y930385I2130J-873D01*
G03X62469Y929867I12J-400D01*
G02X58140Y928313I-2199J-681D01*
G03X57400I-370J-152D01*
G02X53140I-2130J873D01*
G37*
G36*
G01X367087Y917668D02*
G03X367656Y917685I276J289D01*
G02X369561Y918409I1686J-1568D01*
G03X369999Y918798I38J398D01*
G02X372080Y916457I2301J-50D01*
G03X371642Y916068I-38J-398D01*
G02X367754Y914449I-2301J49D01*
G03X367185Y914432I-276J-289D01*
G02X367087Y917668I-1685J1568D01*
G37*
G36*
G01X45739Y905702D02*
G03X45147Y905850I-359J-177D01*
G02X45869Y908738I-1343J1870D01*
G03X46461Y908590I359J177D01*
G02X49721Y907995I1343J-1870D01*
G03X50387I333J221D01*
G02X54082Y908182I1917J-1275D01*
G03X54748Y908256I309J254D01*
G02X58318Y908954I2056J-1036D01*
G03X58910Y909028I263J302D01*
G02X62508Y909268I1894J-1308D01*
G03X63100I296J269D01*
G02Y906172I1704J-1548D01*
G03X62508I-296J-269D01*
G02X59290Y905986I-1704J1548D01*
G03X58698Y905912I-263J-302D01*
G02X55026Y905758I-1894J1308D01*
G03X54360Y905684I-309J-254D01*
G02X50387Y905445I-2056J1036D01*
G03X49721I-333J-221D01*
G02X45739Y905702I-1917J1275D01*
G37*
G36*
G01X364414Y905679D02*
G03X364195Y905193I162J-366D01*
G02X361066Y906604I-2195J-693D01*
G03X361285Y907090I-162J366D01*
G02X364414Y905679I2195J693D01*
G37*
G36*
G01X376775Y904083D02*
G03Y903417I221J-333D01*
G02X374225I-1275J-1917D01*
G03Y904083I-221J333D01*
G02X376775I1275J1917D01*
G37*
G36*
G01X126450Y893170D02*
G03X126250Y892911I-9J-200D01*
G02X121807Y892721I-2196J-691D01*
G03X121611Y892964I-195J43D01*
G02X121559I-26J2302D01*
G03X121356Y892761I-3J-200D01*
G02X116924Y891847I-2302J-41D01*
G03X116184I-370J-152D01*
G02X111924I-2130J873D01*
G03X111184I-370J-152D01*
G02X106767Y892979I-2130J873D01*
G03X106397Y893423I-397J45D01*
G02X104908Y894111I158J2297D01*
G03X104279Y894037I-286J-280D01*
G02X103950Y896829I-1975J1183D01*
G03X104579Y896903I286J280D01*
G02X108841Y895461I1975J-1183D01*
G03X109211Y895017I397J-45D01*
G02X109247Y895014I-173J-2296D01*
G03X109447Y895294I17J199D01*
G02X113661I2107J926D01*
G03X113861Y895014I183J-81D01*
G02X113897Y895017I209J-2293D01*
G03X114267Y895461I-27J399D01*
G02X118810Y895261I2287J259D01*
G03X119010Y895022I196J-39D01*
G02X119095I43J-2302D01*
G03X119298Y895225I3J200D01*
G02X123673Y896268I2302J42D01*
G03X124406Y896298I360J174D01*
G02X128852Y895599I2148J-828D01*
G03X129229Y895222I400J23D01*
G02X126798Y892965I-129J-2298D01*
G03X126595Y893168I-200J3D01*
G02X126450Y893170I-41J2302D01*
G37*
G36*
G01X394878Y897382D02*
G03X394838Y897952I-299J265D01*
G02X395008Y901590I1492J1753D01*
G03X395034Y902226I-229J328D01*
G02X398797Y904157I1466J1774D01*
G03X399241Y903787I399J27D01*
G02X398987Y899256I259J-2287D01*
G03X398518Y898990I-89J-390D01*
G02X398052Y898178I-2188J716D01*
G03X398092Y897608I299J-265D01*
G02X398532Y894604I-1492J-1753D01*
G03X398680Y894033I336J-218D01*
G02X398744Y890002I-1080J-2033D01*
G03X398581Y889484I199J-347D01*
G02X395356Y890498I-2081J-984D01*
G03X395519Y891016I-199J347D01*
G02X395668Y893251I2081J984D01*
G03X395520Y893822I-336J218D01*
G02X394878Y897382I1080J2033D01*
G37*
G36*
G01X333598Y887598D02*
G03X333553Y887025I255J-308D01*
G02X330360Y887273I-1725J-1525D01*
G03X330405Y887846I-255J308D01*
G02X333598Y887598I1725J1525D01*
G37*
G36*
G01X53249Y880989D02*
G03X53337Y880463I338J-214D01*
G02X49951Y879899I-1441J-1795D01*
G03X49863Y880425I-338J214D01*
G02X53249Y880989I1441J1795D01*
G37*
G36*
G01X40433Y884922D02*
G03X40056Y884545I23J-400D01*
G02X39222Y882897I-2298J128D01*
G03X39141Y882370I254J-309D01*
G02X38825Y879474I-1930J-1255D01*
G03X38828Y878901I281J-285D01*
G02X35618Y878883I-1596J-1659D01*
G03X35615Y879456I-281J285D01*
G02X35747Y882892I1596J1659D01*
G03X35828Y883419I-254J309D01*
G02X37629Y886972I1930J1255D01*
G03X38006Y887349I-23J400D01*
G02X40433Y884922I2298J-129D01*
G37*
G36*
G01X74600Y868172D02*
G03X74008I-296J-269D01*
G02Y871268I-1704J1548D01*
G03X74600I296J269D01*
G02Y868172I1704J-1548D01*
G37*
G36*
G01X337453Y869845D02*
G03X337389Y869316I264J-300D01*
G02X334055Y869792I-1889J-1316D01*
G03X334142Y870318I-251J312D01*
G02X337453Y869845I1858J1182D01*
G37*
G36*
G01X670925Y863229D02*
G03X671221Y863673I-100J387D01*
G02X674075Y861771I2279J327D01*
G03X673779Y861327I100J-387D01*
G02X670925Y863229I-2279J-327D01*
G37*
G36*
G01X9559Y855842D02*
G03X9530Y855220I236J-323D01*
G02X6641Y855358I-1530J-1720D01*
G03X6670Y855980I-236J323D01*
G02X9559Y855842I1530J1720D01*
G37*
G36*
G01X722734Y850285D02*
G03X722481Y849786I128J-379D01*
G02X719166Y851465I-2481J-786D01*
G03X719419Y851964I-128J379D01*
G02X722734Y850285I2481J786D01*
G37*
G36*
G01X768457Y847705D02*
G03X768520Y847112I296J-268D01*
G02X765243Y846919I-1520J-2112D01*
G03X765236Y847516I-270J295D01*
G02X768457Y847705I1514J1734D01*
G37*
G36*
G01X114396Y833694D02*
G03X114503Y833135I329J-227D01*
G02X111326Y832528I-1281J-1913D01*
G03X111219Y833087I-329J227D01*
G02X114396Y833694I1281J1913D01*
G37*
G36*
G01X152434Y814217D02*
G03X152966I266J298D01*
G02Y810783I1534J-1717D01*
G03X152434I-266J-298D01*
G02Y814217I-1534J1717D01*
G37*
G36*
G01X147960Y806440D02*
G03X147931Y805848I254J-309D01*
G02X144844Y806000I-1627J-1628D01*
G03X144873Y806592I-254J309D01*
G02X147960Y806440I1627J1628D01*
G37*
G36*
G01X298500Y799000D02*
X290500Y791000D01*
X179000D01*
X159000Y811000D01*
Y865032D01*
G03X158437Y865397I-400J0D01*
G02Y869603I-937J2103D01*
G03X159000Y869968I163J365D01*
G01Y897500D01*
X161500Y900000D01*
X207000D01*
X209500Y902500D01*
X286000D01*
X298500Y890000D01*
Y799000D01*
G37*
G36*
G01X852550Y776277D02*
G03X851950I-300J-264D01*
G02X848560Y780167I-1950J1723D01*
G03Y780833I-222J333D01*
G02X851950Y784723I1440J2167D01*
G03X852550I300J264D01*
G02X855940Y780833I1950J-1723D01*
G03Y780167I222J-333D01*
G02X852550Y776277I-1440J-2167D01*
G37*
G36*
G01X82723Y763296D02*
G03X82922Y763014I182J-83D01*
G02X82992Y763019I199J-2293D01*
G03X83371Y763431I-21J399D01*
G02X85792Y761205I2301J73D01*
G03X85413Y760793I21J-399D01*
G02X80919Y761419I-2301J-73D01*
G03X80550Y761940I-381J121D01*
G02X82723Y763296I74J2301D01*
G37*
G36*
G01X68089Y758491D02*
G03X67550Y758175I-143J-373D01*
G02X63328Y759736I-2278J328D01*
G03X63240Y760262I-338J214D01*
G02X65859Y764035I1442J1794D01*
G03X66463Y764358I205J344D01*
G02X70540Y762777I2299J-119D01*
G03X70562Y762245I309J-254D01*
G02X68089Y758491I-1652J-1603D01*
G37*
G36*
G01X741567Y758002D02*
G03X741647Y757336I256J-307D01*
G02X738833Y756998I-1147J-2336D01*
G03X738753Y757664I-256J307D01*
G02X738630Y762271I1147J2336D01*
G03X738781Y762822I-195J350D01*
G02X742092Y762101I1987J1162D01*
G03X741999Y761537I230J-328D01*
G02X741567Y758002I-2099J-1537D01*
G37*
G36*
G01X219346Y724601D02*
G03X219150Y725269I-287J278D01*
G02X222169Y725684I969J4140D01*
G03X222160Y724988I193J-351D01*
G02X219346Y724601I-1160J-1988D01*
G37*
G36*
G01X70232Y720785D02*
G03X69684Y720797I-280J-285D01*
G02X69761Y724152I-1537J1714D01*
G03X70309Y724140I280J285D01*
G02X70232Y720785I1537J-1714D01*
G37*
G36*
G01X677374Y696701D02*
G03X676958Y696369I-22J-399D01*
G02X674814Y699050I-2270J382D01*
G03X675230Y699382I22J399D01*
G02X677374Y696701I2270J-382D01*
G37*
G36*
G01X771723Y679550D02*
G03Y678950I264J-300D01*
G02X768277I-1723J-1950D01*
G03Y679550I-264J300D01*
G02X771723I1723J1950D01*
G37*
G36*
G01X51903Y658392D02*
G03X52212Y657792I345J-202D01*
G02X50039Y656706I-212J-2292D01*
G03X49745Y657313I-341J210D01*
G02X51903Y658392I255J2187D01*
G37*
G36*
G01X765486Y646766D02*
G03X764894Y646692I-263J-302D01*
G02X764514Y649734I-1894J1308D01*
G03X765106Y649808I263J302D01*
G02X765486Y646766I1894J-1308D01*
G37*
G36*
G01X671468Y577606D02*
G03X670832I-318J-243D01*
G02Y580394I-1832J1394D01*
G03X671468I318J243D01*
G02Y577606I1832J-1394D01*
G37*
G36*
G01X731966Y566783D02*
G03X731434I-266J-298D01*
G02Y570217I-1534J1717D01*
G03X731966I266J298D01*
G02Y566783I1534J-1717D01*
G37*
G36*
G01X817966Y562283D02*
G03X817434I-266J-298D01*
G02Y565717I-1534J1717D01*
G03X817966I266J298D01*
G02Y562283I1534J-1717D01*
G37*
G36*
G01X719329Y562350D02*
G03X718787Y562289I-238J-321D01*
G02X718407Y565633I-1751J1495D01*
G03X718949Y565694I238J321D01*
G02X719329Y562350I1751J-1495D01*
G37*
G36*
G01X773776Y480470D02*
G03X774364Y480448I304J259D01*
G02X774248Y477334I1636J-1620D01*
G03X773660Y477356I-304J-259D01*
G02X773776Y480470I-1636J1620D01*
G37*
G36*
G01X817053Y471274D02*
G03X816420Y471230I-300J-265D01*
G02X816094Y474161I-1920J1270D01*
G03X816721Y474256I277J288D01*
G02X817053Y471274I2279J-1256D01*
G37*
G36*
G01X872048Y446296D02*
G03Y445704I269J-296D01*
G02X868952I-1548J-1704D01*
G03Y446296I-269J296D01*
G02X872048I1548J1704D01*
G37*
G36*
G01X754333Y429560D02*
G03X753667I-333J-222D01*
G02X750122Y433207I-2167J1440D01*
G03X750202Y433820I-212J339D01*
G02X754254Y437059I1897J1780D01*
G03X754907Y437046I331J225D01*
G02X758957Y437215I2093J-1546D01*
G03X759570Y437228I301J263D01*
G02X763228Y433570I2030J-1628D01*
G03X763215Y432957I250J-312D01*
G02X763450Y432723I-1715J-1957D01*
G03X764050I300J264D01*
G02Y429277I1950J-1723D01*
G03X763450I-300J-264D01*
G02X759333Y429560I-1950J1723D01*
G03X758667I-333J-222D01*
G02X754333I-2167J1440D01*
G37*
G36*
G01X1080483Y431862D02*
G03X1080496Y431196I228J-329D01*
G02X1077617Y431138I-1396J-2196D01*
G03X1077604Y431804I-228J329D01*
G02X1080483Y431862I1396J2196D01*
G37*
G36*
G01X903202Y437498D02*
Y397002D01*
X899498Y393298D01*
X881002D01*
X880284Y394016D01*
X880173Y393987D01*
G02X877298Y397887I-673J2513D01*
G01Y402303D01*
X877171Y402353D01*
G02Y406647I829J2147D01*
G01X877298Y406697D01*
Y432952D01*
G03X876766Y433329I-400J0D01*
G02Y437671I-766J2171D01*
G03X877298Y438048I132J377D01*
G01Y443498D01*
X881002Y447202D01*
X893498D01*
X903202Y437498D01*
G37*
G36*
G01X1062719Y397271D02*
G03X1062655Y396742I264J-300D01*
G02X1059247Y397155I-1889J-1316D01*
G03X1059311Y397684I-264J300D01*
G02X1062719Y397271I1889J1316D01*
G37*
G36*
G01X74347Y386464D02*
X73619D01*
G02Y389488I-1736J1512D01*
G01X74347D01*
G02Y386464I1736J-1512D01*
G37*
G36*
G01X64795Y386309D02*
X64553Y386302D01*
X64496Y386238D01*
G02X64410Y389404I-1713J1538D01*
G01X64471Y389343D01*
X64713Y389350D01*
X64770Y389414D01*
G02X64856Y386248I1713J-1538D01*
G01X64795Y386309D01*
G37*
G36*
G01X45413Y389489D02*
G03X45946Y389490I266J299D01*
G02X45953Y386056I1537J-1714D01*
G03X45420Y386055I-266J-299D01*
G02X45413Y389489I-1537J1714D01*
G37*
G36*
G01X55291Y386213D02*
X55229Y386273D01*
X55000Y386260D01*
X54945Y386194D01*
G02X54774Y389339I-1762J1481D01*
G01X54837Y389279D01*
X55066Y389292D01*
X55122Y389358D01*
G02X55291Y386213I1761J-1482D01*
G37*
G36*
G01X983908Y385638D02*
G03X983375Y385438I-168J-363D01*
G02X979085Y388262I-2375J1062D01*
G03X979018Y388861I-295J270D01*
G02X981592Y393362I1481J2139D01*
G03X982125Y393562I168J363D01*
G02X986415Y390738I2375J-1062D01*
G03X986482Y390139I295J-270D01*
G02X983908Y385638I-1481J-2139D01*
G37*
G36*
G01X157386Y325219D02*
Y324849D01*
X157449Y324790D01*
G02X154299I-1575J-1679D01*
G01X154362Y324849D01*
Y325219D01*
X154299Y325278D01*
G02X157449I1575J1679D01*
G01X157386Y325219D01*
G37*
G36*
G01X184352Y319454D02*
G03X184008Y319925I-393J74D01*
G02X186557Y321783I287J2284D01*
G03X186901Y321312I393J-74D01*
G02X188327Y320566I-287J-2284D01*
G03X188872Y320518I298J267D01*
G02X190138Y321006I1424J-1809D01*
G03X190508Y321450I-27J399D01*
G02X192952Y319412I2287J259D01*
G03X192582Y318968I27J-399D01*
G02X188582Y317171I-2287J-259D01*
G03X188037Y317219I-298J-267D01*
G02X184352Y319454I-1423J1809D01*
G37*
G36*
G01X157386Y316069D02*
Y315699D01*
X157449Y315640D01*
G02X154299I-1575J-1679D01*
G01X154362Y315699D01*
Y316069D01*
X154299Y316128D01*
G02X157449I1575J1679D01*
G01X157386Y316069D01*
G37*
G36*
G01X190524Y297784D02*
G03X190968Y297488I387J100D01*
G02X191166Y297507I319J-2280D01*
G03X191543Y297884I-23J400D01*
G02X193970Y295457I2298J-129D01*
G03X193593Y295080I23J-400D01*
G02X189066Y294634I-2298J129D01*
G03X188622Y294930I-387J-100D01*
G02X187760Y294970I-326J2279D01*
G03X187278Y294674I-93J-389D01*
G02X185574Y297448I-2239J535D01*
G03X186056Y297744I93J389D01*
G02X190524Y297784I2239J-535D01*
G37*
G36*
G01X211995Y293398D02*
X211625D01*
X211566Y293334D01*
G02Y296484I-1679J1575D01*
G01X211625Y296420D01*
X211995D01*
X212054Y296484D01*
G02Y293334I1679J-1575D01*
G01X211995Y293398D01*
G37*
G36*
G01X202547D02*
X202177D01*
X202118Y293334D01*
G02Y296484I-1679J1575D01*
G01X202177Y296420D01*
X202547D01*
X202606Y296484D01*
G02Y293334I1679J-1575D01*
G01X202547Y293398D01*
G37*
G36*
G01X177350D02*
X176980D01*
X176921Y293334D01*
G02Y296484I-1679J1575D01*
G01X176980Y296420D01*
X177350D01*
X177409Y296484D01*
G02Y293334I1679J-1575D01*
G01X177350Y293398D01*
G37*
G36*
G01X167901Y292798D02*
X167531D01*
X167472Y292734D01*
G02Y295884I-1679J1575D01*
G01X167531Y295820D01*
X167901D01*
X167960Y295884D01*
G02Y292734I1679J-1575D01*
G01X167901Y292798D01*
G37*
G36*
G01X1035966Y223783D02*
G03X1035434I-266J-298D01*
G02Y227217I-1534J1717D01*
G03X1035966I266J298D01*
G02Y223783I1534J-1717D01*
G37*
G36*
G01X309166Y162288D02*
X306384D01*
X306353Y162278D01*
G02Y165322I-501J1522D01*
G01X306384Y165312D01*
X309166D01*
X309197Y165322D01*
G02Y162278I501J-1522D01*
G01X309166Y162288D01*
G37*
G36*
G01X316716Y154488D02*
X313934D01*
X313903Y154478D01*
G02Y157522I-501J1522D01*
G01X313934Y157512D01*
X316716D01*
X316747Y157522D01*
G02Y154478I501J-1522D01*
G01X316716Y154488D01*
G37*
G36*
G01X327934Y151975D02*
Y149476D01*
X327944Y149445D01*
G02X324900I-1522J-501D01*
G01X324910Y149476D01*
Y151975D01*
X324900Y152006D01*
G02X327944I1522J501D01*
G01X327934Y151975D01*
G37*
G36*
G01X321312Y146366D02*
Y143584D01*
X321322Y143553D01*
G02X318278I-1522J-501D01*
G01X318288Y143584D01*
Y146366D01*
X318278Y146397D01*
G02X321322I1522J501D01*
G01X321312Y146366D01*
G37*
G36*
G01X735238Y139512D02*
G03X734738Y139246I-117J-382D01*
G02X733010Y142488I-2490J754D01*
G03X733510Y142754I117J382D01*
G02X735238Y139512I2490J-754D01*
G37*
G36*
G01X685455Y130816D02*
G03X684992Y130363I-67J-394D01*
G02X682861Y132544I-2574J-383D01*
G03X683324Y132997I67J394D01*
G02X685455Y130816I2574J383D01*
G37*
G36*
G01X700338Y127417D02*
G03X699727Y127211I-230J-328D01*
G02X696216Y130388I-2479J789D01*
G03X696382Y130988I-159J367D01*
G02X701102Y132530I2118J1512D01*
G03X701545Y132137I400J4D01*
G02X700338Y127417I283J-2587D01*
G37*
G36*
G01X1092156Y124988D02*
X1091766D01*
X1091707Y124925D01*
G02Y128075I-1679J1575D01*
G01X1091766Y128012D01*
X1092156D01*
X1092215Y128075D01*
G02Y124925I1679J-1575D01*
G01X1092156Y124988D01*
G37*
G36*
G01X676045Y101604D02*
G03X676061Y101043I293J-272D01*
G02X672782Y100946I-1592J-1663D01*
G03X672766Y101507I-293J272D01*
G02X676045Y101604I1592J1663D01*
G37*
G36*
G01X708646Y83703D02*
G03X709312Y83696I335J218D01*
G02X709286Y81147I1904J-1294D01*
G03X708620Y81154I-335J-218D01*
G02X708646Y83703I-1904J1294D01*
G37*
G36*
G01X1057796Y74452D02*
G03X1057204I-296J-269D01*
G02X1053952Y77704I-1704J1548D01*
G03Y78296I-269J296D01*
G02X1057204Y81548I1548J1704D01*
G03X1057796I296J269D01*
G02X1061417Y81275I1704J-1548D01*
G03X1062083I333J221D01*
G02X1065704Y81548I1917J-1275D01*
G03X1066296I296J269D01*
G02X1069548Y78296I1704J-1548D01*
G03Y77704I269J-296D01*
G02X1066296Y74452I-1548J-1704D01*
G03X1065704I-296J-269D01*
G02X1062083Y74725I-1704J1548D01*
G03X1061417I-333J-221D01*
G02X1057796Y74452I-1917J1275D01*
G37*
G36*
G01X1019050Y73777D02*
G03X1018450I-300J-264D01*
G02Y77223I-1950J1723D01*
G03X1019050I300J264D01*
G02Y73777I1950J-1723D01*
G37*
G36*
G01X686820Y57375D02*
G03X686917Y56847I340J-210D01*
G02X683560Y56228I-1398J-1828D01*
G03X683463Y56756I-340J210D01*
G02X683718Y60582I1398J1828D01*
G03X683886Y61088I-199J347D01*
G02X687143Y60002I2114J912D01*
G03X686975Y59496I199J-347D01*
G02X686820Y57375I-2114J-912D01*
G37*
G36*
G01X384050Y51277D02*
G03X383450I-300J-264D01*
G02X380060Y55167I-1950J1723D01*
G03Y55833I-222J333D01*
G02X382940I1440J2167D01*
G03Y55167I222J-333D01*
G02X383450Y54723I-1439J-2168D01*
G03X384050I300J264D01*
G02Y51277I1950J-1723D01*
G37*
G36*
G01X1072448Y40156D02*
X1069284D01*
G02Y46378I-2355J3111D01*
G01X1072448D01*
G02Y40156I2355J-3111D01*
G37*
G36*
G01X350440Y36333D02*
G03Y35667I222J-333D01*
G02X347560I-1440J-2167D01*
G03Y36333I-222J333D01*
G02X350440I1440J2167D01*
G37*
G36*
G01X331940D02*
G03Y35667I222J-333D01*
G02X329060I-1440J-2167D01*
G03Y36333I-222J333D01*
G02X331940I1440J2167D01*
G37*
G36*
G01X387870Y12627D02*
G03X387130I-370J-152D01*
G02X383362Y15117I-2130J873D01*
G03X383077Y15798I-284J281D01*
G01X382502D01*
X379298Y19002D01*
Y41998D01*
X382502Y45202D01*
X402998D01*
X405702Y42498D01*
Y25711D01*
G02Y21533I-2749J-2089D01*
G01Y18502D01*
X402998Y15798D01*
X391923D01*
G03X391638Y15117I-1J-400D01*
G02X387870Y12627I-1638J-1617D01*
G37*
G36*
G01X317950Y9277D02*
G02Y12723I-1950J1723D01*
G03X318550I300J264D01*
G02X321106Y13530I1949J-1723D01*
G03X321572Y14063I93J389D01*
G02X322277Y16950I2428J937D01*
G03Y17550I-264J300D01*
G02Y21450I1723J1950D01*
G03Y22050I-264J300D01*
G02X325723I1723J1950D01*
G03Y21450I264J-300D01*
G02Y17550I-1723J-1950D01*
G03Y16950I264J-300D01*
G02X323394Y12470I-1723J-1950D01*
G03X322928Y11937I-93J-389D01*
G02X318550Y9277I-2428J-937D01*
G03X317950I-300J-264D01*
G37*
G36*
G01X1024884Y50457D02*
G02Y52543I-2384J1043D01*
G03X1025616I366J161D01*
G02Y50457I2384J-1043D01*
G03X1024884I-366J-161D01*
G37*
G36*
G01X603557Y68942D02*
G02Y71294I-3616J1176D01*
G03X604317I380J123D01*
G02X611549I3616J-1176D01*
G03X612309I380J123D01*
G02X619541I3616J-1176D01*
G03X620301I380J123D01*
G02X627533I3616J-1176D01*
G03X628293I380J123D01*
G02X635525I3616J-1176D01*
G03X636285I380J123D01*
G02Y68942I3616J-1176D01*
G03X635525I-380J-123D01*
G02X628293I-3616J1176D01*
G03X627533I-380J-123D01*
G02X620301I-3616J1176D01*
G03X619541I-380J-123D01*
G02X612309I-3616J1176D01*
G03X611549I-380J-123D01*
G02X604317I-3616J1176D01*
G03X603557I-380J-123D01*
G37*
G36*
G01X599521Y78942D02*
G02Y81294I-3616J1176D01*
G03X600281I380J123D01*
G02X607513I3616J-1176D01*
G03X608273I380J123D01*
G02Y78942I3616J-1176D01*
G03X607513I-380J-123D01*
G02X600281I-3616J1176D01*
G03X599521I-380J-123D01*
G37*
G36*
G01X631569D02*
G02Y81294I-3616J1176D01*
G03X632329I380J123D01*
G02X639561I3616J-1176D01*
G03X640321I380J123D01*
G02Y78942I3616J-1176D01*
G03X639561I-380J-123D01*
G02X632329I-3616J1176D01*
G03X631569I-380J-123D01*
G37*
G36*
G01X830543Y382384D02*
G02X828457I-1043J-2384D01*
G03Y383116I-161J366D01*
G02X830543I1043J2384D01*
G03Y382384I161J-366D01*
G37*
G36*
G01X845703Y506901D02*
G02X841754Y509993I-2403J999D01*
G03X841741Y510646I-238J322D01*
G02X841298Y514576I1459J2154D01*
G03X841285Y515136I-292J273D01*
G02X845465Y518086I1815J1864D01*
G03X846197Y518099I363J167D01*
G02X850502Y515324I2403J-999D01*
G03X850515Y514764I292J-273D01*
G02X850246Y510807I-1815J-1864D01*
G03X850259Y510154I238J-322D01*
G02X846435Y506914I-1459J-2154D01*
G03X845703Y506901I-363J-167D01*
G37*
G36*
G01X739882Y584088D02*
G02X739284Y581826I1618J-1638D01*
G03X738618Y582002I-385J-108D01*
G02X739216Y584264I-1618J1638D01*
G03X739882Y584088I385J108D01*
G37*
G36*
G01X594543Y650884D02*
G02X592457I-1043J-2384D01*
G03Y651616I-161J366D01*
G02Y656384I1043J2384D01*
G03Y657116I-161J366D01*
G02X594543I1043J2384D01*
G03Y656384I161J-366D01*
G02Y651616I-1043J-2384D01*
G03Y650884I161J-366D01*
G37*
G36*
G01X600543D02*
G02X598457I-1043J-2384D01*
G03Y651616I-161J366D01*
G02Y656384I1043J2384D01*
G03Y657116I-161J366D01*
G02X600543I1043J2384D01*
G03Y656384I161J-366D01*
G02Y651616I-1043J-2384D01*
G03Y650884I161J-366D01*
G37*
G36*
G01X78353Y726037D02*
X78378Y726023D01*
G02X75253Y722898I-1106J-2019D01*
G01X75239Y722923D01*
X70530Y727632D01*
Y747060D01*
X73230Y749760D01*
Y758171D01*
X73222Y758198D01*
G02X77642I2210J646D01*
G01X77634Y758171D01*
Y747936D01*
X74934Y745236D01*
Y737759D01*
G03X75348Y737359I400J0D01*
G02X77484Y736101I84J-2300D01*
G03X78201Y736108I357J181D01*
G02X81600Y736983I2071J-1005D01*
G03X82130Y737044I231J327D01*
G02X85701Y736881I1719J-1531D01*
G03X86281Y736813I322J237D01*
G02X89734Y736264I1491J-1754D01*
G03X90413Y736261I340J209D01*
G02X90403Y733835I1952J-1221D01*
G03X89724Y733838I-340J-209D01*
G02X85920Y733691I-1952J1221D01*
G03X85340Y733759I-322J-237D01*
G02X82521Y733633I-1491J1754D01*
G03X81991Y733572I-231J-327D01*
G02X78220Y734061I-1719J1531D01*
G03X77503Y734054I-357J-181D01*
G02X75348Y732759I-2071J1005D01*
G03X74934Y732359I-14J-400D01*
G01Y729456D01*
X78353Y726037D01*
G37*
G36*
G01X606286Y876257D02*
G02X606231Y878839I-2286J1243D01*
G03X606925Y878854I343J206D01*
G02X606980Y876272I2286J-1243D01*
G03X606286Y876257I-343J-206D01*
G37*
G36*
G01X496637Y882246D02*
G02Y883754I-1637J754D01*
G03X497363I363J167D01*
G02Y882246I1637J-754D01*
G03X496637I-363J-167D01*
G37*
G36*
G01X88701Y774868D02*
G02X86552Y777017I-2297J-148D01*
G01X86643Y777011D01*
X87048Y777417D01*
Y795937D01*
G03X86435Y796275I-400J0D01*
G02X85402Y795927I-1230J1945D01*
G03X85047Y795438I35J-399D01*
G02X82606Y797213I-2243J-518D01*
G03X82961Y797702I-35J399D01*
G02X86435Y800165I2243J518D01*
G03X87048Y800503I213J338D01*
G01Y806746D01*
G03X86375Y807038I-400J0D01*
G02X84158Y806510I-1572J1682D01*
G01X84131Y806518D01*
X82616D01*
X64400Y788302D01*
X59945D01*
X59918Y788294D01*
G02X57253Y789398I-646J2210D01*
G01X57239Y789423D01*
X52402Y794260D01*
Y822052D01*
X54285Y823935D01*
G03X54154Y824588I-283J283D01*
G02X57154Y827588I868J2132D01*
G03X57807Y827457I370J152D01*
G01X62086Y831735D01*
G03X61803Y832418I-283J283D01*
G02X60100Y833172I1J2302D01*
G03X59508I-296J-269D01*
G02X57672Y837018I-1704J1548D01*
G03X58048Y837417I-24J399D01*
G01Y860423D01*
X52543Y865929D01*
X52452Y865923D01*
G02X50909Y870051I-148J2297D01*
G03X50864Y870718I-242J319D01*
G02X54281Y872408I1136J2002D01*
G01X54267Y872309D01*
X63256Y863321D01*
Y837776D01*
G03X63938Y837493I400J0D01*
G01X67567Y841122D01*
X77845D01*
X79000Y839967D01*
X80513Y841480D01*
X90011D01*
X94037Y837453D01*
G02X94320Y837115I-1730J-1736D01*
G03X95048Y837343I328J228D01*
G01Y838101D01*
X106899Y849952D01*
X108713D01*
G02X112630Y849373I1787J-1452D01*
G03X113370I370J152D01*
G02X115352Y846203I2130J-873D01*
G01X115261Y846209D01*
X113671Y844618D01*
X111602D01*
G03X111202Y844219I0J-400D01*
G02X107444Y842662I-2202J1D01*
G03X106878I-283J-283D01*
G01X100344Y836128D01*
Y834862D01*
G03X101026Y834579I400J0D01*
G01X102399Y835952D01*
X103213D01*
G02X103534Y832725I1787J-1452D01*
G01X103394Y832841D01*
X89952Y819399D01*
Y776215D01*
X88695Y774959D01*
X88701Y774868D01*
G37*
G36*
G01X674583Y966475D02*
G03X673917I-333J-221D01*
G02Y969025I-1917J1275D01*
G03X674583I333J221D01*
G02Y966475I1917J-1275D01*
G37*
G36*
G01X280248Y957817D02*
G03X280611Y957299I382J-118D01*
G02X278302Y955683I-111J-2299D01*
G03X277939Y956201I-382J118D01*
G02X276339Y956960I111J2299D01*
G03X275692Y956886I-297J-268D01*
G02X275389Y959540I-2014J1114D01*
G03X276036Y959614I297J268D01*
G02X280248Y957817I2014J-1115D01*
G37*
G36*
G01X390300Y953815D02*
G03X390327Y953287I313J-249D01*
G02X386971Y953047I-1577J-1537D01*
G03X386922Y953574I-323J236D01*
G02X390300Y953815I1578J1676D01*
G37*
G36*
G01X405693Y949744D02*
G03X405497Y949501I-1J-200D01*
G02X400963Y949259I-2247J-501D01*
G03X400593Y949703I-397J45D01*
G02X398463Y952259I157J2297D01*
G03X398093Y952703I-397J45D01*
G02X400537Y954741I157J2297D01*
G03X400907Y954297I397J-45D01*
G02X402852Y952939I-157J-2297D01*
G03X403585Y952946I365J163D01*
G02X408002Y952175I2119J-900D01*
G03X408379Y951798I400J23D01*
G02X405948Y949541I-129J-2298D01*
G03X405745Y949744I-200J3D01*
G02X405693I-26J2302D01*
G37*
G36*
G01X416796Y946952D02*
G03X416204I-296J-269D01*
G02X412667Y949893I-1704J1548D01*
G03X412625Y950424I-318J242D01*
G02X411914Y952010I1590J1665D01*
G03X411364Y952366I-400J-14D01*
G02X410759Y956787I-864J2134D01*
G03X411203Y957157I45J397D01*
G02X413371Y959298I2297J-157D01*
G03X413748Y959675I-23J400D01*
G02X414723Y961430I2298J-129D01*
G03X414716Y962089I-230J327D01*
G02X417704Y965548I1284J1911D01*
G03X418296I296J269D01*
G02Y962452I1704J-1548D01*
G03X417704I-296J-269D01*
G02X417323Y962116I-1704J1548D01*
G03X417330Y961457I230J-327D01*
G02X416175Y957248I-1284J-1911D01*
G03X415798Y956871I23J-400D01*
G02X414706Y955039I-2298J129D01*
G03X414812Y954312I210J-341D01*
G02X416048Y950696I-597J-2223D01*
G03X416090Y950165I318J-242D01*
G02X416204Y950048I-1591J-1664D01*
G03X416796I296J269D01*
G02X419971Y950271I1704J-1548D01*
G03X420503Y950290I255J308D01*
G02X420627Y946859I1595J-1660D01*
G03X420095Y946840I-255J-308D01*
G02X416796Y946952I-1595J1660D01*
G37*
G36*
G01X388461Y944145D02*
G03X388485Y944767I-239J321D01*
G02X391377Y944655I1515J1733D01*
G03X391353Y944033I239J-321D01*
G02X388461Y944145I-1515J-1733D01*
G37*
G36*
G01X422615Y225730D02*
G03X422212Y225301I-4J-400D01*
G02X419233Y225443I-1498J-110D01*
G03X418873Y225908I-394J67D01*
G02X420481Y227152I127J1497D01*
G03X420841Y226687I394J-67D01*
G02X420937Y226675I-138J-1496D01*
G03X421162Y226915I29J198D01*
G02X422615Y225730I1468J317D01*
G37*
G36*
G01X284978Y178331D02*
G03X284458Y178025I-127J-379D01*
G02X280557Y180729I-2558J475D01*
G03X280544Y181421I-207J342D01*
G02X280237Y185780I1256J2279D01*
G03Y186420I-240J320D01*
G02X284368Y188919I1563J2080D01*
G03X284874Y188599I395J64D01*
G02X286905Y183849I726J-2499D01*
G03X286932Y183143I201J-346D01*
G02X284978Y178331I-1131J-2343D01*
G37*
G36*
G01X324042Y117181D02*
G03X323387I-328J-229D01*
G02Y119819I-1887J1319D01*
G03X324042I327J229D01*
G02X327663Y120014I1887J-1319D01*
G03X328266I301J263D01*
G02Y116986I1734J-1514D01*
G03X327663I-301J-263D01*
G02X324042Y117181I-1734J1514D01*
G37*
G36*
G01X428301Y231166D02*
G02X427983Y229842I1143J-975D01*
G03X427290Y230008I-389J-94D01*
G02X427608Y231332I-1143J975D01*
G03X428301Y231166I389J94D01*
G37*
G36*
G01X400645Y219353D02*
G02X398961I-842J-1244D01*
G03Y220015I-224J331D01*
G02X400645I842J1244D01*
G03Y219353I224J-331D01*
G37*
G36*
G01X391598Y217267D02*
G02X389512Y219353I-1244J842D01*
G03Y220015I-224J331D01*
G02X389511Y222502I842J1244D01*
G03Y223165I-224J331D01*
G02X391197I843J1243D01*
G03Y222502I224J-332D01*
G02X391196Y220015I-843J-1243D01*
G03Y219353I224J-331D01*
G02X391598Y218951I-842J-1244D01*
G03X392260I331J224D01*
G02Y217267I1244J-842D01*
G03X391598I-331J-224D01*
G37*
G36*
G01X407347Y214114D02*
G02X407339Y215798I-1248J836D01*
G03X408001Y215801I330J226D01*
G02X408009Y214117I1248J-836D01*
G03X407347Y214114I-330J-226D01*
G37*
G36*
G01X426243Y198369D02*
G02X424157Y200455I-1244J842D01*
G03Y201117I-224J331D01*
G02X426243Y203203I842J1244D01*
G03X426905I331J224D01*
G02X428991Y201117I1244J-842D01*
G03Y200455I224J-331D01*
G02X426905Y198369I-842J-1244D01*
G03X426243I-331J-224D01*
G37*
G36*
G01X397495Y200455D02*
G02X395812I-841J-1244D01*
G03Y201118I-224J332D01*
G02X395811Y203605I842J1244D01*
G03Y204267I-224J331D01*
G02X395409Y204669I842J1244D01*
G03X394747Y204668I-331J-225D01*
G02X392661Y206754I-1244J842D01*
G03Y207416I-224J331D01*
G02X392660Y209903I842J1244D01*
G03Y210566I-224J331D01*
G02X394747Y212651I843J1243D01*
G03X395410I331J224D01*
G02X397496Y210566I1244J-841D01*
G03X397495Y209904I224J-331D01*
G02X397897Y209502I-842J-1244D01*
G03X398559I331J224D01*
G02Y207818I1244J-842D01*
G03X397897I-331J-224D01*
G02X397496Y207417I-1243J842D01*
G03Y206754I224J-332D01*
G02Y204268I-843J-1243D01*
G03Y203606I224J-331D01*
G02X397495Y201118I-842J-1244D01*
G03Y200455I224J-331D01*
G37*
G36*
G01X375849Y188920D02*
G02X373763Y191006I-1243J843D01*
G03Y191669I-224J331D01*
G02X375849Y193755I843J1243D01*
G03X376512I332J224D01*
G02X376913Y194156I1243J-842D01*
G03Y194818I-224J331D01*
G02X376912Y197305I842J1244D01*
G03Y197968I-224J332D01*
G02X376913Y200455I843J1243D01*
G03Y201117I-224J331D01*
G02X378597I842J1244D01*
G03Y200455I224J-331D01*
G02X378598Y197968I-842J-1244D01*
G03Y197305I224J-331D01*
G02X378597Y194818I-843J-1243D01*
G03Y194156I224J-331D01*
G02X378598Y191669I-842J-1244D01*
G03Y191006I224J-331D01*
G02X376512Y188920I-843J-1243D01*
G03X375849I-332J-224D01*
G37*
G36*
G01X429393Y182621D02*
G02Y184305I-1244J842D01*
G03X430055I331J224D01*
G02X430457Y184707I1244J-842D01*
G03Y185369I-224J331D01*
G02X432542Y187456I842J1244D01*
G03X433205I331J224D01*
G02Y185770I1243J-843D01*
G03X432542I-332J-224D01*
G02X432141Y185369I-1243J842D01*
G03Y184707I224J-331D01*
G02X430055Y182621I-842J-1244D01*
G03X429393I-331J-224D01*
G37*
G36*
G01X384920Y153222D02*
G02X383236Y153201I-826J-1254D01*
G03X383228Y153863I-229J328D01*
G02X383212Y156360I827J1254D01*
G03Y157023I-224J332D01*
G02X385298Y159109I843J1243D01*
G03X385963Y159114I331J225D01*
G02X385976Y157447I1256J-824D01*
G03X385311Y157442I-331J-225D01*
G02X384898Y157023I-1256J824D01*
G03Y156360I224J-331D01*
G02X384912Y153884I-843J-1243D01*
G03X384920Y153222I229J-328D01*
G37*
G36*
G01X336112Y130000D02*
X336122Y129969D01*
G02X333078I-1522J-501D01*
G01X333088Y130000D01*
Y132499D01*
X333078Y132530D01*
G02X335339Y134453I1522J501D01*
G03X335918Y134743I184J355D01*
G02X336757Y133142I1482J-244D01*
G03X336189Y132831I-171J-361D01*
G02X336122Y132530I-1590J196D01*
G01X336112Y132499D01*
Y130000D01*
G37*
G36*
G01X328163Y127144D02*
G02X327777Y129072I-2234J555D01*
G03X328464Y129149I321J239D01*
G02X328826Y127338I1465J-649D01*
G03X328163Y127144I-275J-290D01*
G37*
G36*
G01X423500Y127705D02*
G02X422217Y126529I186J-1490D01*
G03X421776Y127010I-391J84D01*
G02X423059Y128186I-186J1490D01*
G03X423500Y127705I391J-84D01*
G37*
G36*
G01X429393Y170023D02*
G02Y171707I-1244J842D01*
G03X430055I331J224D01*
G02Y170023I1244J-842D01*
G03X429393I-331J-224D01*
G37*
G36*
G01X435692Y166873D02*
G02Y168559I-1243J843D01*
G03X436355I331J224D01*
G02Y166873I1243J-843D01*
G03X435692I-332J-224D01*
G37*
G36*
G01X426243Y160574D02*
G02Y162258I-1244J842D01*
G03X426905I331J224D01*
G02X427306Y162659I1243J-842D01*
G03Y163322I-224J331D01*
G02X429393Y165407I843J1243D01*
G03X430055I331J224D01*
G02X432142Y163322I1244J-842D01*
G03Y162659I224J-332D01*
G02X432543Y162258I-842J-1243D01*
G03X433205Y162259I331J225D01*
G02X435692Y162260I1244J-842D01*
G03X436355I331J224D01*
G02Y160574I1243J-843D01*
G03X435692I-332J-224D01*
G02X433205Y160575I-1243J843D01*
G03X432543Y160574I-331J-225D01*
G02X430055I-1244J842D01*
G03X429393I-331J-224D01*
G02X426905I-1244J842D01*
G03X426243I-331J-224D01*
G37*
G36*
G01X455494Y155785D02*
G02X454285Y154707I237J-1483D01*
G03X453836Y155210I-385J108D01*
G02X455045Y156288I-237J1483D01*
G03X455494Y155785I385J-108D01*
G37*
G36*
G01X444776Y143778D02*
G02X443019Y143789I-886J-1213D01*
G03X443023Y144437I-232J325D01*
G02X442662Y144812I885J1214D01*
G03X442001Y144817I-332J-223D01*
G02X442012Y146508I-1236J854D01*
G03X442673Y146503I332J223D01*
G02X443081Y146903I1236J-853D01*
G03X443085Y147568I-220J334D01*
G02X443094Y150060I843J1243D01*
G03X443086Y150731I-222J333D01*
G02X443049Y153243I805J1268D01*
G03X443059Y153899I-224J331D01*
G02X443075Y156349I877J1219D01*
G03X443061Y157013I-230J327D01*
G02X443041Y159530I810J1265D01*
G03X443047Y160193I-221J334D01*
G02X443029Y162654I852J1237D01*
G03Y163306I-232J326D01*
G02X443085Y165792I870J1224D01*
G03X443081Y166466I-217J336D01*
G02X444696Y166475I800J1271D01*
G03X444700Y165801I217J-336D01*
G02X444769Y163306I-801J-1271D01*
G03Y162654I232J-326D01*
G02X444729Y160178I-870J-1224D01*
G03X444723Y159515I221J-334D01*
G02X444732Y157047I-852J-1237D01*
G03X444746Y156383I230J-327D01*
G02X444778Y153874I-810J-1265D01*
G03X444768Y153218I224J-331D01*
G02X444725Y150750I-877J-1219D01*
G03X444733Y150079I222J-333D01*
G02X444756Y147558I-805J-1268D01*
G03X444752Y146893I220J-334D01*
G02X444780Y144426I-843J-1243D01*
G03X444776Y143778I232J-325D01*
G37*
G36*
G01X458164Y133984D02*
G02X456509Y132991I-235J-1484D01*
G03X456194Y133516I-378J130D01*
G02X455002Y135469I235J1484D01*
G03X454633Y135994I-380J125D01*
G02X453457Y138373I43J1501D01*
G03X453300Y138970I-324J234D01*
G02X455148Y139456I629J1364D01*
G03X455305Y138859I324J-234D01*
G02X456103Y137026I-629J-1364D01*
G03X456472Y136501I380J-125D01*
G02X457849Y134509I-43J-1501D01*
G03X458164Y133984I378J-130D01*
G37*
G36*
G01X450022Y127162D02*
G02X447491Y127442I-1353J-652D01*
G03X447222Y128087I-314J248D01*
G02X448625Y130433I167J1493D01*
G03X449218Y130359I329J227D01*
G02X450346Y127734I991J-1129D01*
G03X450022Y127162I36J-398D01*
G37*
G36*
G01X441035Y124357D02*
G02X438164Y125102I-1495J143D01*
G03X437829Y125662I-366J161D01*
G02X439321Y126557I116J1497D01*
G03X439656Y125997I366J-161D01*
G02X440243Y125828I-113J-1498D01*
G03X440828Y126143I187J353D01*
G02X441134Y126918I1495J-142D01*
G03X440841Y127562I-316J245D01*
G02X442120Y128143I90J1499D01*
G03X442413Y127499I316J-245D01*
G02X441620Y124672I-90J-1499D01*
G03X441035Y124357I-187J-353D01*
G37*
G36*
G01X433764Y122130D02*
G02X431288Y123829I-1224J870D01*
G03X431037Y124442I-333J221D01*
G02X432600Y125082I311J1469D01*
G03X432851Y124469I333J-221D01*
G02X433764Y123870I-311J-1469D01*
G03X434416I326J232D01*
G02Y122130I1224J-870D01*
G03X433764I-326J-232D01*
G37*
G36*
G01X1062377Y175781D02*
G03X1062435Y175249I325J-234D01*
G02X1059032Y174879I-1535J-1715D01*
G03X1058974Y175411I-325J234D01*
G02X1062377Y175781I1535J1715D01*
G37*
G36*
G01X1039733Y135915D02*
G03X1039082Y135855I-304J-259D01*
G02X1038837Y138494I-1997J1145D01*
G03X1039488Y138554I304J259D01*
G02X1042699Y139365I1997J-1145D01*
G03X1043224Y139457I211J340D01*
G02X1043817Y136075I1807J-1426D01*
G03X1043292Y135983I-211J-340D01*
G02X1039733Y135915I-1807J1426D01*
G37*
G36*
G01X1168130Y231127D02*
G02Y232873I-2130J873D01*
G03X1168870I370J152D01*
G02Y231127I2130J-873D01*
G03X1168130I-370J-152D01*
G37*
G36*
G01X1130884Y227957D02*
G02Y230043I-2384J1043D01*
G03X1131616I366J161D01*
G02Y227957I2384J-1043D01*
G03X1130884I-366J-161D01*
G37*
G36*
G01X1241003Y211521D02*
G02X1238571Y211254I-1003J-2072D01*
G03X1238497Y211928I-248J314D01*
G02X1239162Y216277I1003J2072D01*
G03X1239356Y216983I-58J396D01*
G02X1239806Y221312I1644J2017D01*
G03X1239939Y221911I-184J355D01*
G02X1239551Y224380I2061J1589D01*
G03X1239218Y224913I-376J136D01*
G02X1241450Y229223I282J2587D01*
G03X1242050I300J264D01*
G02X1244686Y224990I1950J-1723D01*
G03X1244420Y224457I106J-386D01*
G02X1243194Y221188I-2420J-957D01*
G03X1243061Y220589I184J-355D01*
G02X1241262Y216411I-2061J-1589D01*
G03X1241035Y215715I40J-398D01*
G02X1240929Y212195I-1535J-1715D01*
G03X1241003Y211521I248J-314D01*
G37*
G36*
G01X1041802Y150986D02*
G02X1038083Y152814I-2302J14D01*
G03X1038079Y153449I-246J316D01*
G02X1038042Y157091I1389J1835D01*
G03X1038046Y157715I-248J314D01*
G02X1041802Y159514I1454J1785D01*
G03X1042468Y159218I400J3D01*
G02X1045275Y155583I1532J-1718D01*
G03Y154917I221J-333D01*
G02X1042468Y151282I-1275J-1917D01*
G03X1041802Y150986I-266J-299D01*
G37*
G36*
G01X1059057Y152545D02*
G02X1056916Y152531I-1057J-2045D01*
G03X1056911Y153239I-189J353D01*
G02X1055671Y155434I1057J2045D01*
G03X1055009Y155762I-399J26D01*
G02X1054775Y155583I-1513J1735D01*
G03Y154917I221J-333D01*
G02X1052225I-1275J-1917D01*
G03Y155583I-221J333D01*
G02X1051204Y157332I1275J1917D01*
G03X1050533Y157596I-399J-29D01*
G02X1050516Y157580I-1586J1668D01*
G03Y156988I269J-296D01*
G02X1050243Y153367I-1548J-1704D01*
G03Y152701I221J-333D01*
G02X1047693I-1275J-1917D01*
G03Y153367I-221J333D01*
G02X1047420Y156988I1275J1917D01*
G03Y157580I-269J296D01*
G02X1051264Y159452I1548J1704D01*
G03X1051935Y159188I399J29D01*
G02X1055032Y159218I1565J-1688D01*
G03X1055698Y159514I266J299D01*
G02X1059426Y157693I2302J-14D01*
G03X1059422Y157069I248J-314D01*
G02X1059052Y153253I-1454J-1785D01*
G03X1059057Y152545I189J-353D01*
G37*
G36*
G01X1096143Y904633D02*
G03X1095563Y904478I-222J-333D01*
G02X1094780Y907413I-2063J1022D01*
G03X1095360Y907568I222J333D01*
G02X1096143Y904633I2063J-1022D01*
G37*
G36*
G01X1210959Y875666D02*
X1210973Y875641D01*
X1213202Y873412D01*
Y848173D01*
X1213210Y848146D01*
G02X1210354Y845290I-2210J-646D01*
G01X1210327Y845298D01*
X1196673D01*
X1196646Y845290D01*
G02Y849710I-646J2210D01*
G01X1196673Y849702D01*
X1208798D01*
Y871588D01*
X1208028Y872358D01*
X1196845D01*
X1196811Y872346D01*
G02X1194894Y876519I-810J2155D01*
G01X1194919Y876533D01*
X1195148Y876762D01*
X1195570D01*
X1195587Y876765D01*
G02X1196413I413J-2265D01*
G01X1196430Y876762D01*
X1208267D01*
X1208294Y876770D01*
G02X1210959Y875666I646J-2210D01*
G37*
G36*
G01X1167432Y857685D02*
G02X1166734Y855593I1568J-1686D01*
G03X1166068Y855815I-394J-71D01*
G02X1166766Y857907I-1568J1686D01*
G03X1167432Y857685I394J71D01*
G37*
G36*
G01X1108318Y755613D02*
G03X1108288Y754980I229J-328D01*
G02X1105288Y755247I-1688J-1980D01*
G03X1105370Y755875I-201J346D01*
G02X1108318Y755613I1630J1625D01*
G37*
G36*
G01X1139820Y705788D02*
G02X1136916Y705531I-1420J-488D01*
G03X1136475Y705990I-395J62D01*
G02X1136499Y708971I-172J1492D01*
G03X1136923Y709515I52J397D01*
G02X1136874Y709661I1397J550D01*
G03X1136295Y709903I-385J-108D01*
G02X1137016Y711623I-725J1315D01*
G03X1137595Y711381I385J108D01*
G02X1139770Y709674I725J-1315D01*
G03X1140273Y709187I386J-105D01*
G02X1140306Y706303I437J-1437D01*
G03X1139820Y705788I-108J-385D01*
G37*
G36*
G01X1155278Y681028D02*
G02X1153340Y681183I-1060J-1064D01*
G03X1153389Y681790I-234J324D01*
G02X1153206Y682011I1060J1064D01*
G03X1152543I-331J-224D01*
G02X1150056Y682012I-1243J843D01*
G03X1149394I-331J-224D01*
G02X1147308Y684098I-1244J842D01*
G03Y684760I-224J331D01*
G02X1147307Y687247I842J1244D01*
G03Y687910I-224J331D01*
G02X1147308Y690397I843J1243D01*
G03Y691059I-224J331D01*
G02X1147307Y693546I842J1244D01*
G03Y694209I-224J331D01*
G02X1147308Y696696I843J1243D01*
G03Y697358I-224J331D01*
G02X1149394Y699444I842J1244D01*
G03X1150056I331J224D01*
G02X1152543Y699445I1244J-842D01*
G03X1153206I332J224D01*
G02X1155693Y699444I1243J-843D01*
G03X1156355I331J224D01*
G02X1158842Y699445I1244J-842D01*
G03X1159505I332J224D01*
G02X1161992Y699444I1243J-843D01*
G03X1162654I331J224D01*
G02X1164740Y697358I1244J-842D01*
G03Y696696I224J-331D01*
G02X1164741Y694209I-842J-1244D01*
G03Y693546I224J-332D01*
G02X1164740Y691059I-843J-1243D01*
G03Y690397I224J-331D01*
G02X1164741Y687910I-842J-1244D01*
G03Y687247I224J-332D01*
G02X1162654Y685162I-843J-1243D01*
G03X1161992I-331J-224D01*
G02X1161590Y684760I-1244J842D01*
G03Y684098I224J-331D01*
G02X1159906I-842J-1244D01*
G03Y684760I-224J331D01*
G02X1159505Y685161I842J1243D01*
G03X1158842I-331J-224D01*
G02X1156355Y685162I-1243J843D01*
G03X1155693I-331J-224D01*
G02X1155291Y684760I-1244J842D01*
G03Y684098I224J-331D01*
G02X1155327Y681635I-842J-1244D01*
G03X1155278Y681028I234J-324D01*
G37*
G36*
G01X1355000Y412000D02*
X1357500Y409500D01*
Y379500D01*
X1355000Y377000D01*
X1332000D01*
X1329500Y379500D01*
Y409500D01*
X1332000Y412000D01*
X1355000D01*
G37*
G36*
G01X1354050Y525075D02*
G03X1354511Y524767I391J86D01*
G02X1352750Y522125I389J-2167D01*
G03X1352289Y522433I-391J-86D01*
G02X1354050Y525075I-389J2167D01*
G37*
G36*
G01X1342381Y432863D02*
G03X1341819I-281J-284D01*
G02X1338563Y436119I-1619J1637D01*
G03Y436681I-284J281D01*
G02X1341686Y440058I1636J1620D01*
G03X1342233Y440088I258J306D01*
G02X1345489Y436835I1667J-1587D01*
G03X1345504Y436243I276J-289D01*
G02X1342381Y432863I-1504J-1743D01*
G37*
G36*
G01X1332363Y430045D02*
G03X1332163Y429446I133J-377D01*
G02X1329137Y430455I-2163J-1446D01*
G03X1329337Y431054I-133J377D01*
G02X1332363Y430045I2163J1446D01*
G37*
G36*
G01X1379940Y362833D02*
G03Y362167I222J-333D01*
G02X1377060I-1440J-2167D01*
G03Y362833I-222J333D01*
G02Y367167I1440J2167D01*
G03Y367833I-222J333D01*
G02X1376777Y371950I1440J2167D01*
G03Y372550I-264J300D01*
G02X1376337Y375946I1723J1950D01*
G03X1376137Y376545I-333J222D01*
G02X1375560Y381167I863J2455D01*
G03Y381833I-222J333D01*
G02X1378440I1440J2167D01*
G03Y381167I222J-333D01*
G02X1379163Y377554I-1440J-2167D01*
G03X1379363Y376955I333J-222D01*
G02X1380223Y372550I-863J-2455D01*
G03Y371950I264J-300D01*
G02X1379940Y367833I-1723J-1950D01*
G03Y367167I222J-333D01*
G02Y362833I-1440J-2167D01*
G37*
G36*
G01X1356550Y344777D02*
G03X1355950I-300J-264D01*
G02X1352277Y348450I-1950J1723D01*
G03Y349050I-264J300D01*
G02X1355950Y352723I1723J1950D01*
G03X1356550I300J264D01*
G02X1360223Y349050I1950J-1723D01*
G03Y348450I264J-300D01*
G02X1356550Y344777I-1723J-1950D01*
G37*
G36*
G01X1352056Y277536D02*
G03X1352722Y277462I357J180D01*
G02X1352444Y274964I1778J-1462D01*
G03X1351778Y275038I-357J-180D01*
G02X1352056Y277536I-1778J1462D01*
G37*
G36*
G01X1349508Y114874D02*
G03X1349804Y114282I349J-196D01*
G02X1347492Y113126I-304J-2282D01*
G03X1347196Y113718I-349J196D01*
G02X1349508Y114874I304J2282D01*
G37*
G36*
G01X1345753Y590714D02*
G02X1343481I-1136J-2002D01*
G03Y591410I-197J348D01*
G02X1346619Y594548I1136J2002D01*
G03X1347315I348J197D01*
G02Y592276I2002J-1136D01*
G03X1346619I-348J-197D01*
G02X1345753Y591410I-2002J1136D01*
G03Y590714I197J-348D01*
G37*
G36*
G01X1354546Y534094D02*
G02X1353216Y535645I-2146J-494D01*
G03X1353754Y536106I148J372D01*
G02X1355084Y534555I2146J494D01*
G03X1354546Y534094I-148J-372D01*
G37*
G36*
G01X1361543Y477384D02*
G02X1359457I-1043J-2384D01*
G03Y478116I-161J366D01*
G02X1361543I1043J2384D01*
G03Y477384I161J-366D01*
G37*
G36*
G01X1355543D02*
G02X1353457I-1043J-2384D01*
G03Y478116I-161J366D01*
G02X1355543I1043J2384D01*
G03Y477384I161J-366D01*
G37*
G36*
G01X1376766Y392591D02*
G02X1375068Y391742I234J-2591D01*
G03X1374734Y392409I-297J268D01*
G02X1376432Y393258I-234J2591D01*
G03X1376766Y392591I297J-268D01*
G37*
G36*
G01X1381630Y273627D02*
G02Y275373I-2130J873D01*
G03X1382370I370J152D01*
G02Y273627I2130J-873D01*
G03X1381630I-370J-152D01*
G37*
G36*
G01X1368384Y252957D02*
G02X1364957Y256384I-2384J1043D01*
G03Y257116I-161J366D01*
G02X1364277Y261450I1043J2384D01*
G03Y262050I-264J300D01*
G02X1368384Y265043I1723J1950D01*
G03X1369116I366J161D01*
G02X1373223Y262050I2384J-1043D01*
G03Y261450I264J-300D01*
G02X1372543Y257116I-1723J-1950D01*
G03Y256384I161J-366D01*
G02X1369116Y252957I-1043J-2384D01*
G03X1368384I-366J-161D01*
G37*
G54D41*
X425278Y802000D03*
X444778Y802100D03*
X438278D03*
X431778Y802000D03*
X431278Y883000D03*
X444278D03*
X437778D03*
X456278Y802100D03*
X450778Y883000D03*
X460778D03*
X475778Y802100D03*
X462778D03*
X469278D03*
X473778Y883000D03*
X467278D03*
X480278D03*
X330900Y134500D03*
X347000Y120040D03*
X340000D03*
X338000Y127500D03*
X368336Y189755D03*
X368307Y196062D03*
Y202361D03*
X374606Y211810D03*
X392240Y129000D03*
X383680Y129030D03*
X384055Y202361D03*
X380906Y211810D03*
X402950Y133050D03*
X402800Y129180D03*
X412403Y142520D03*
X412401Y205510D03*
X402953Y211810D03*
X412402D03*
X412767Y233162D03*
X418940Y125000D03*
X413540Y128500D03*
X418702Y142520D03*
X425001D03*
X418701Y211810D03*
X425001D03*
X431300Y142520D03*
X434449Y180314D03*
X434414Y205514D03*
X434449Y199212D03*
Y192913D03*
X436500Y241000D03*
X396653Y167715D03*
X390392Y186614D03*
X396654D03*
X396653Y174015D03*
Y180314D03*
X402952Y167715D03*
X409251D03*
X402977Y174003D03*
X402952Y186613D03*
X409251D03*
X409288Y180315D03*
X402952Y180314D03*
X409251Y174015D03*
X428375Y119735D03*
X421876Y167705D03*
X415575Y167703D03*
X421876Y174005D03*
Y180304D03*
Y186603D03*
X415551Y186614D03*
X415587Y180315D03*
X415551Y174015D03*
X451679Y148250D03*
X460300Y141100D03*
X454929Y146500D03*
X451329Y165570D03*
X428542Y400985D03*
Y397048D03*
Y408859D03*
Y404922D03*
X428523Y416683D03*
X440353Y369487D03*
X444290Y365550D03*
Y357676D03*
Y385237D03*
Y377363D03*
X440353Y381300D03*
X436416Y377363D03*
X440353Y400985D03*
Y389174D03*
X432479Y400985D03*
Y397048D03*
Y393111D03*
X444290Y397048D03*
X440353D03*
X436416D03*
X444290Y400985D03*
X436416D03*
X432479Y408859D03*
Y404922D03*
X436416D03*
Y408859D03*
X444290Y404922D03*
Y408859D03*
X440353D03*
Y404922D03*
X444323Y416883D03*
X436523Y416683D03*
X440353Y412796D03*
X432479D03*
X442535Y426770D03*
X434723Y426283D03*
X456103Y365550D03*
Y357676D03*
X460040Y369487D03*
Y361613D03*
X448227Y369487D03*
Y361613D03*
X456103Y385237D03*
Y377363D03*
X460040Y381300D03*
X448227D03*
X460040Y389174D03*
X448227D03*
X456103Y400985D03*
X460040D03*
X456103Y393111D03*
X460040D03*
Y397048D03*
X448227Y400985D03*
Y393111D03*
X456103Y397048D03*
X448227D03*
X456223Y404883D03*
Y408783D03*
X456103Y412796D03*
X460023Y408883D03*
X452123Y416783D03*
X460040Y412796D03*
X448227D03*
X452223Y404883D03*
X448227Y408859D03*
X452223Y408783D03*
X448227Y404922D03*
X450725Y425460D03*
X475788Y369487D03*
Y361613D03*
Y357676D03*
X467914Y369487D03*
Y361613D03*
Y365550D03*
Y357676D03*
Y353739D03*
X463977Y365550D03*
Y357676D03*
X471851Y361613D03*
Y369487D03*
Y353739D03*
Y357676D03*
X463977Y385237D03*
X475788Y381300D03*
Y377363D03*
X467914Y385237D03*
Y377363D03*
Y381300D03*
X463977Y377363D03*
X471851D03*
Y381300D03*
X475788Y400985D03*
Y397048D03*
Y393111D03*
X471851D03*
Y397048D03*
X475788Y389174D03*
X467914Y400985D03*
Y397048D03*
Y393111D03*
Y389174D03*
X463977Y393111D03*
Y397048D03*
Y400985D03*
X471851D03*
Y389174D03*
X463977Y408859D03*
Y404922D03*
X467914Y408859D03*
Y404922D03*
X471851Y412796D03*
X475788D03*
X471851Y416733D03*
X467914Y412796D03*
X475788Y424607D03*
X483662Y357676D03*
X483663Y365463D03*
X483662Y361613D03*
X483683Y369403D03*
X479725Y369487D03*
Y361613D03*
Y365550D03*
Y357676D03*
Y381300D03*
Y385237D03*
Y377363D03*
Y397048D03*
Y389174D03*
Y400985D03*
Y393111D03*
X483662Y408859D03*
X479725Y412796D03*
X483662D03*
Y404922D03*
X479725Y416733D03*
X483662Y424607D03*
X440353Y341928D03*
X444290D03*
Y345865D03*
X448227Y330117D03*
Y334054D03*
Y341928D03*
X448000Y346000D03*
X1118630Y714820D03*
X1132398Y720624D03*
X1141868Y680064D03*
X1144880Y707720D03*
X1152090Y677010D03*
X1169800Y682200D03*
G54D47*
X334500Y118500D03*
X421000Y231500D03*
X457500Y121000D03*
X436416Y357676D03*
X458685Y425710D03*
X466655Y425340D03*
X472055Y425000D03*
G54D39*
X153937Y238898D03*
Y246772D03*
Y260551D03*
X224015Y246772D03*
Y260551D03*
G54D38*
X146364Y296000D03*
X207100Y703600D03*
X222000Y703500D03*
X225000Y920500D03*
X232000Y921000D03*
X344000Y27000D03*
X336000D03*
X351929Y266000D03*
X601000Y543000D03*
X609500Y778500D03*
X603000D03*
Y785000D03*
X609000Y870000D03*
X626500Y557350D03*
X645500Y481000D03*
X674666Y82002D03*
X670998Y116010D03*
X670000Y395000D03*
X670500Y414000D03*
X701949Y118331D03*
X730748Y99500D03*
X740000Y109534D03*
Y681000D03*
X757802Y474000D03*
X782600Y411000D03*
X792000Y356500D03*
X801500Y573000D03*
X829500Y373500D03*
X858500Y656500D03*
X889000Y617000D03*
X895000Y617500D03*
X930500Y536500D03*
X943500Y488000D03*
X1034500Y51500D03*
X1060000Y929500D03*
X1085000Y434000D03*
X1032000Y110000D03*
X1065000Y154000D03*
X1091500Y846500D03*
X1354500Y486500D03*
X1360500D03*
X1374500Y402000D03*
X1372500Y415000D03*
G54D50*
X1367067Y96260D03*
G54D48*
X1272441Y7087D03*
X1299213D03*
G54D36*
X58804Y699720D03*
X111000Y981500D03*
X176938Y680465D03*
X182500Y677500D03*
X238500Y705000D03*
X253500Y707250D03*
X339000Y878500D03*
Y894000D03*
Y885500D03*
X387061Y986061D03*
X389500Y992000D03*
X599000Y804000D03*
X622500Y696500D03*
X625000Y706000D03*
X632500Y530000D03*
X862500Y65000D03*
X865000Y488500D03*
X874000Y56000D03*
X873500Y61500D03*
X881000Y736500D03*
X945000Y141500D03*
X947500Y153000D03*
X1027504Y853366D03*
X337300Y949500D03*
X379500Y963500D03*
X1084500Y223500D03*
X1141100Y831600D03*
X1196000Y710500D03*
X1218040Y719850D03*
G54D43*
X590315Y9134D03*
Y19134D03*
X649527Y9134D03*
Y19134D03*
Y29134D03*
G54D42*
X501000Y876000D03*
G54D35*
X35304Y832220D03*
X34304Y897720D03*
X44804Y837220D03*
X44500Y851500D03*
X49000Y861500D03*
X42554Y891720D03*
X41304Y927220D03*
X55304Y669720D03*
X58804Y710220D03*
X62704Y739620D03*
X55304Y746220D03*
X76804Y710220D03*
X70909Y847325D03*
X89804Y669720D03*
X95304Y686220D03*
X94804Y708220D03*
X99804Y709220D03*
X85304Y768720D03*
X93347Y765754D03*
X95700Y926300D03*
X105804Y943220D03*
X108804Y938795D03*
X115500Y983500D03*
X127654Y293453D03*
X132123Y318877D03*
X123654Y320953D03*
X131500Y324000D03*
X122906Y331953D03*
X130000Y666500D03*
X129304Y798720D03*
X122500Y845500D03*
X128000Y870500D03*
X145500Y283500D03*
X143500Y710500D03*
X141054Y795820D03*
X150225Y790412D03*
X162500Y670000D03*
X163000Y710500D03*
X152500Y840000D03*
X194500Y724000D03*
X212500Y716500D03*
X204500Y721000D03*
X230000Y680500D03*
X322229Y218800D03*
X316129Y213000D03*
X328000Y285000D03*
X321500Y688000D03*
X362210Y876200D03*
X371000Y866500D03*
X376041Y866041D03*
X377464Y987493D03*
X377250Y982250D03*
X391000Y866500D03*
X404500Y877300D03*
X414000Y8000D03*
X438500Y9000D03*
X488000Y904500D03*
X483500Y907500D03*
X623500Y576500D03*
X622500Y608500D03*
X628524Y591976D03*
X654300Y490300D03*
X669025Y441725D03*
X663500Y610500D03*
X670474Y808700D03*
X676748Y52000D03*
X684197Y74703D03*
X687500Y440500D03*
X688500Y606000D03*
X683000Y603950D03*
X677500Y612000D03*
X680000Y640000D03*
X691000Y704500D03*
X682968Y758284D03*
X677500Y773500D03*
X678468Y805284D03*
X691300Y807300D03*
X679000Y865050D03*
X705500Y575600D03*
X702918Y782734D03*
X704000Y892500D03*
X716034Y53966D03*
X716466Y65466D03*
X720216Y82138D03*
X725000Y452300D03*
X709750Y585200D03*
X719918Y754734D03*
X715118Y776134D03*
X717468Y810784D03*
X722000Y808500D03*
X720500Y860000D03*
X710750Y863250D03*
X714000Y867500D03*
X714500Y891000D03*
X740500Y75000D03*
X732500Y455500D03*
X736000Y464500D03*
X728500Y482500D03*
X730000Y536500D03*
X735500Y771984D03*
X736000Y810500D03*
X733768Y800734D03*
X741050Y869500D03*
X740000Y886000D03*
X737290Y903000D03*
X754500Y67500D03*
X751484Y540600D03*
X755000Y727500D03*
X757500Y743500D03*
X757000Y896400D03*
X758500Y457000D03*
X774500Y489500D03*
X760500D03*
X766000Y635000D03*
X771000Y689500D03*
X760500Y707950D03*
X768000Y728000D03*
X763500Y839500D03*
X768000Y833000D03*
X774500Y890500D03*
X779000Y458000D03*
X788774Y482774D03*
X786500Y575688D03*
X786032Y570468D03*
X783500Y649000D03*
X784804Y673304D03*
X779500Y705000D03*
X785000Y892000D03*
X785500Y969700D03*
X798000Y400500D03*
X796074Y479000D03*
X803500Y655000D03*
X798000Y706000D03*
X802000Y724000D03*
X801750Y867500D03*
X808500Y363500D03*
X823500Y480000D03*
Y556500D03*
X821250Y845750D03*
X810500Y851000D03*
X832000Y137500D03*
X833500Y613000D03*
X835000Y719000D03*
X826500Y743000D03*
X849500Y622000D03*
X846500Y710000D03*
X845500Y865000D03*
X873000Y68500D03*
X857500Y485500D03*
X862500Y621250D03*
X859500Y629500D03*
X872000Y636000D03*
X867500Y655200D03*
X860718Y683684D03*
X887940Y380200D03*
X877000Y479500D03*
X876000Y631700D03*
X881000Y710000D03*
X903075Y472000D03*
X918420Y449130D03*
X907000Y465050D03*
X923000Y51500D03*
X924465Y388465D03*
X936030Y457540D03*
X937000Y489000D03*
X935400Y597300D03*
X944000Y434000D03*
X980490Y198827D03*
X982075Y439500D03*
X1003000Y59500D03*
X988900Y434800D03*
X1007532Y902468D03*
X1023600Y173000D03*
X1031524Y218476D03*
X1030000Y403500D03*
X1032657Y901500D03*
X1027716Y914784D03*
X1032200Y921500D03*
X1040000Y182000D03*
X1068500Y118500D03*
X1069000Y124500D03*
X1181500Y949000D03*
X1314500Y921500D03*
X268178Y955500D03*
X338000Y942000D03*
X339500Y936500D03*
Y960000D03*
X333500Y954000D03*
X354000Y960000D03*
X376000D03*
X383500Y938500D03*
X430500Y962000D03*
X666750Y961550D03*
X268300Y219800D03*
X450929Y118000D03*
X471290Y118361D03*
X471429Y133500D03*
X1020500Y142000D03*
X1033500Y118000D03*
X1025500Y129500D03*
X1033500Y124000D03*
X1034000Y155000D03*
X1066500Y185500D03*
X1074500D03*
X1072500Y208924D03*
X1186500Y232000D03*
X1208000Y231000D03*
X1207500Y239500D03*
X1201922Y248500D03*
X1239500Y204000D03*
X1071500Y739000D03*
X1077500Y759000D03*
X1093000Y791000D03*
X1097500Y784500D03*
X1098500Y823344D03*
X1092718Y859984D03*
X1111000Y836000D03*
X1107160Y843160D03*
X1177000Y860000D03*
X1111500Y718500D03*
X1107000Y763000D03*
X1196500Y736687D03*
X1210500Y733500D03*
X1332000Y459250D03*
X1347000Y88000D03*
X1343500Y112000D03*
X1343000Y466500D03*
X1358500Y288916D03*
X1362500Y459000D03*
X1353500Y466500D03*
X1351000Y455750D03*
X1355500Y556500D03*
X1360817Y557812D03*
X1353117Y610412D03*
X1369720Y106365D03*
X1381500Y292000D03*
X1376000D03*
X1375500Y328000D03*
X1370500Y356500D03*
X1368000Y450500D03*
X1374500Y462800D03*
X1369617Y557012D03*
X1384500Y331500D03*
G54D33*
X945197Y380000D03*
X968819D03*
G54D49*
X1379862Y108465D03*
Y119095D03*
G54D37*
X121890Y269528D03*
X131890D03*
X141890D03*
G54D30*
X35435Y373228D03*
X82675D03*
X180118Y729409D03*
Y739409D03*
X200118Y729409D03*
X190118D03*
X200118Y739409D03*
X190118D03*
X210118Y729409D03*
Y739409D03*
X230118Y729409D03*
Y739409D03*
X220118D03*
X250118Y729409D03*
X240118D03*
X250118Y739409D03*
X240118D03*
X260118Y729409D03*
Y739409D03*
X270118Y729409D03*
Y739409D03*
G54D29*
X21220Y373228D03*
X96890D03*
X157480Y283071D03*
X220472D03*
G54D46*
X1057086Y43267D03*
X1084646D03*
G54D40*
X413189Y23622D03*
X423425D03*
G54D28*
X1008268Y411417D03*
G54D44*
X585315Y44134D03*
X654527D03*
G54D45*
X1045000Y32598D03*
X1096732D03*
G54D32*
X743897Y410629D03*
X1376968Y147243D03*
Y216535D03*
G54D31*
X600925Y44134D03*
X638917D03*
G54D34*
X19272Y337795D03*
Y396850D03*
X98838Y337795D03*
Y396850D03*
%LPD*%
G75*
G36*
G01X60184Y792706D02*
X56806Y796084D01*
Y798862D01*
G02X57289Y799253I400J0D01*
G03X59934Y800712I483J2251D01*
G02X60484Y800934I375J-137D01*
G03X63279Y801552I1008J2070D01*
G01X69170D01*
X86366Y818748D01*
G02X87048Y818465I282J-283D01*
G01Y810694D01*
G02X86375Y810402I-400J0D01*
G03X84158Y810930I-1572J-1682D01*
G01X84131Y810922D01*
X80792D01*
X62576Y792706D01*
X60184D01*
G37*
G36*
G01X57289Y803755D02*
G02X56805Y804146I-84J391D01*
G01Y813020D01*
G02X57220Y813420I400J0D01*
G03X58818Y813986I84J2300D01*
G02X59410Y813912I263J-302D01*
G03X59790Y816954I1894J1308D01*
G02X59198Y817028I-263J302D01*
G03X57220Y818020I-1894J-1308D01*
G02X56806Y818420I-14J400D01*
G01Y820228D01*
X63081Y826504D01*
G02X63737Y826366I283J-283D01*
G03X67755Y825521I2285J888D01*
G01X71783Y829548D01*
X77500D01*
G03X79436Y833504I0J2452D01*
G02X79646Y834135I316J245D01*
G03X80733Y834767I-647J2364D01*
G01X81400Y835433D01*
G02X82059Y835288I283J-282D01*
G03X86521Y836162I2162J791D01*
G02X86921Y836576I400J14D01*
G01X87981D01*
X90571Y833987D01*
G03X94657Y835031I1734J1733D01*
G01X94699Y835174D01*
X95048D01*
Y834365D01*
X68305Y807622D01*
X61299D01*
X57463Y803786D01*
X57400Y803776D01*
G03X57289Y803755I372J-2272D01*
G37*
G36*
G01X68006Y834627D02*
X69597Y836218D01*
X75815D01*
X76899Y835134D01*
G02X76616Y834452I-283J-282D01*
G01X69753D01*
X68688Y833387D01*
G02X68006Y833670I-282J283D01*
G01Y834627D01*
G37*
G36*
G01X180000Y795000D02*
X162500Y812500D01*
Y894500D01*
X165500Y897500D01*
X194300D01*
G02X194700Y897085I0J-400D01*
G03X199300I2300J-85D01*
G02X199700Y897500I400J15D01*
G01X202800D01*
G02X203200Y897085I0J-400D01*
G03X207800I2300J-85D01*
G02X208200Y897500I400J15D01*
G01X209000D01*
X211000Y899500D01*
X228865D01*
G02X229255Y899011I0J-400D01*
G03X233745I2245J-511D01*
G02X234135Y899500I390J89D01*
G01X282500D01*
X293000Y889000D01*
Y801500D01*
X286500Y795000D01*
X180000D01*
G37*
G36*
G01X383000Y17000D02*
X380500Y19500D01*
Y41500D01*
X383000Y44000D01*
X402500D01*
X404500Y42000D01*
Y27299D01*
G02X403981Y26917I-400J0D01*
G03Y20327I-1028J-3295D01*
G02X404500Y19945I119J-382D01*
G01Y19000D01*
X402500Y17000D01*
X383000D01*
G37*
G36*
G01X427278Y868000D02*
X433778Y874500D01*
X479778D01*
X484778Y869500D01*
Y828000D01*
X479778Y823000D01*
X432278D01*
X427278Y828000D01*
Y868000D01*
G37*
G36*
G01X881500Y394500D02*
X878500Y397500D01*
Y402248D01*
X878644Y402290D01*
G03Y406710I-644J2210D01*
G01X878500Y406752D01*
Y407754D01*
G03Y411246I-1500J1746D01*
G01Y443000D01*
X881500Y446000D01*
X893000D01*
X902000Y437000D01*
Y397500D01*
X899000Y394500D01*
X881500D01*
G37*
%LPC*%
G75*
G36*
G01X244950Y884723D02*
G03X245550I300J264D01*
G02X249450I1950J-1723D01*
G03X250050I300J264D01*
G02X253950I1950J-1723D01*
G03X254550I300J264D01*
G02X258450I1950J-1723D01*
G03X259050I300J264D01*
G02X262950I1950J-1723D01*
G03X263550I300J264D01*
G02Y881277I1950J-1723D01*
G03X262950I-300J-264D01*
G02X259050I-1950J1723D01*
G03X258450I-300J-264D01*
G02X254550I-1950J1723D01*
G03X253950I-300J-264D01*
G02X250050I-1950J1723D01*
G03X249450I-300J-264D01*
G02X245550I-1950J1723D01*
G03X244950I-300J-264D01*
G02Y884723I-1950J1723D01*
G37*
G36*
G01X169934Y869717D02*
G03X170466I266J298D01*
G02Y866283I1534J-1717D01*
G03X169934I-266J-298D01*
G02Y869717I-1534J1717D01*
G37*
G36*
G01X271275Y868083D02*
G03Y867417I221J-333D01*
G02X268725I-1275J-1917D01*
G03Y868083I-221J333D01*
G02X271275I1275J1917D01*
G37*
G36*
G01X230296Y823452D02*
G03X229704I-296J-269D01*
G02X225944Y823964I-1704J1548D01*
G03X225278Y824038I-357J-180D01*
G02X225556Y826536I-1778J1462D01*
G03X226222Y826462I357J180D01*
G02X229704Y826548I1778J-1462D01*
G03X230296I296J269D01*
G02Y823452I1704J-1548D01*
G37*
G36*
G01X226363Y877045D02*
G03X226157Y876455I133J-377D01*
G02X223253Y872508I-2157J-1455D01*
G02X223137Y877455I747J2492D01*
G03X223345Y878042I-133J377D01*
G02X228099Y879377I2155J1458D01*
G02X226363Y877045I-2599J123D01*
G37*
G54D41*
X442278Y846000D03*
X455278D03*
X451278D03*
X459278D03*
X467278D03*
G54D35*
X174000Y830500D03*
X170500Y835500D03*
X183000Y865750D03*
X191875Y803125D03*
X199000Y891500D03*
X204500Y817500D03*
X215250Y833750D03*
X204000Y862000D03*
X212000Y891500D03*
X218000Y801500D03*
X240000Y829250D03*
X247500Y829500D03*
X236500Y866000D03*
X251000Y835500D03*
X251500Y855500D03*
X261500Y857500D03*
X250362Y865000D03*
X276500Y888500D03*
X885000Y438700D03*
X893500Y427000D03*
%LPD*%
G75*
G54D10*
X8590Y318590D03*
X4500Y329297D03*
Y349297D03*
Y369297D03*
Y389297D03*
Y409297D03*
Y429297D03*
Y449297D03*
Y469297D03*
Y489297D03*
Y509297D03*
Y529297D03*
Y549297D03*
Y569297D03*
Y589297D03*
Y609297D03*
Y629297D03*
Y649297D03*
Y669297D03*
Y689297D03*
Y709297D03*
Y729297D03*
Y749297D03*
Y769297D03*
Y789297D03*
Y809297D03*
Y829297D03*
Y849297D03*
Y869297D03*
Y889297D03*
Y909297D03*
Y929297D03*
Y949297D03*
Y969297D03*
X20000Y380000D03*
Y440000D03*
Y460000D03*
Y480000D03*
Y500000D03*
X25000Y980000D03*
X45000D03*
X55000Y975000D03*
X65000Y980000D03*
X75000Y975000D03*
X95000D03*
X121000Y545500D03*
X140000Y720000D03*
Y740000D03*
X156500Y939500D03*
X162000D03*
X178000Y590000D03*
X180000Y760000D03*
X167500Y939500D03*
X172500D03*
X177500D03*
X182000D03*
X188000D03*
X193500D03*
X199500D03*
X206000Y982000D03*
X220000Y760000D03*
X227500Y957500D03*
Y963500D03*
X226000Y982000D03*
X246968Y957784D03*
X233468Y957284D03*
X239968Y957784D03*
X246968Y963784D03*
X239968D03*
X233468D03*
X246000Y982000D03*
X261500Y188900D03*
X256300Y188800D03*
X258800Y184200D03*
X261400Y179800D03*
X255800Y179600D03*
X259000Y211000D03*
Y206000D03*
X262500Y208500D03*
X260000Y260000D03*
Y760000D03*
X252000Y957500D03*
X252500Y963500D03*
X262178Y976000D03*
X261178Y981040D03*
X278500Y965000D03*
X277500Y969500D03*
X272500D03*
X268000D03*
X285678Y995500D03*
X293178D03*
X299500Y5500D03*
X310929Y257500D03*
X311500Y272000D03*
X301178Y995500D03*
X309678D03*
X321000Y29000D03*
Y33500D03*
Y38000D03*
Y57000D03*
Y52500D03*
Y48000D03*
Y42500D03*
X315929Y253000D03*
X316000Y271500D03*
X315929Y257500D03*
X324678Y995500D03*
X317178D03*
X341178Y996000D03*
X332678Y995500D03*
X355500Y608500D03*
X358268Y995500D03*
X348678Y996000D03*
X370000Y51000D03*
Y55500D03*
Y60000D03*
X370500Y72100D03*
X378500Y812000D03*
Y824500D03*
X377953Y995725D03*
X393800Y25100D03*
X389300Y20100D03*
X393800D03*
X384800Y25100D03*
X389300D03*
X384800Y20100D03*
X391000Y35500D03*
X395500D03*
X393900Y30400D03*
X389400D03*
X384900D03*
X389763Y996085D03*
X398300Y20100D03*
Y25100D03*
X400000Y35500D03*
X398400Y30400D03*
X398000Y39500D03*
X412000Y724000D03*
X409500Y775500D03*
X422500Y764500D03*
X445395Y317610D03*
X431000Y724000D03*
X432678Y827300D03*
X430778Y864000D03*
X435678Y996000D03*
X443178D03*
X453878Y824900D03*
X456278Y866500D03*
X458678Y996000D03*
X450178D03*
X467000Y118500D03*
X477500Y715000D03*
X474178Y995500D03*
X466178Y996000D03*
X491500Y715000D03*
X490500Y800000D03*
X482778Y832000D03*
X482278Y867500D03*
X489678Y995500D03*
X482178D03*
X504500Y715000D03*
X502500Y800000D03*
X505678Y995500D03*
X498178D03*
X521055Y528500D03*
Y533500D03*
X516555Y528500D03*
Y533500D03*
X526055D03*
X526000Y524500D03*
Y529000D03*
X521000Y524000D03*
X521055Y544000D03*
Y548900D03*
X516555Y543500D03*
X516655Y548900D03*
X521055Y538500D03*
X516555Y539000D03*
X526055Y538500D03*
Y544000D03*
Y548900D03*
X516500Y556000D03*
X521178Y995500D03*
X513678D03*
X536678Y996000D03*
X530083Y995500D03*
X560000Y20000D03*
X560678Y996000D03*
X569178D03*
X576678D03*
X584678Y994500D03*
X604500Y714500D03*
X606000Y918500D03*
X598178Y983500D03*
X616500Y714500D03*
X613500Y744500D03*
Y759000D03*
X620500Y848500D03*
X630500Y368500D03*
X634000Y734500D03*
X633500Y749500D03*
X630500Y912000D03*
X650000Y110000D03*
X657500Y827000D03*
X656500Y906000D03*
X670454Y94544D03*
X660000Y120000D03*
X670522Y130200D03*
X690966Y142028D03*
X685000Y150500D03*
X690500Y468000D03*
X682500Y917500D03*
X703053Y133568D03*
X705500Y352500D03*
X708500Y365000D03*
X707000Y385000D03*
Y378000D03*
X708500Y371000D03*
X694000Y483500D03*
X693500Y472000D03*
X694000Y492000D03*
Y500500D03*
Y507500D03*
Y514000D03*
X711500Y385000D03*
Y378000D03*
X720000Y905000D03*
X727248Y141500D03*
X746716Y130238D03*
X750916Y130272D03*
X760522Y116784D03*
X770000Y123500D03*
X771000Y958500D03*
X766600D03*
X762100Y958600D03*
X771500Y963500D03*
X767100D03*
X762600Y963600D03*
X771400Y968900D03*
X767000D03*
X762500Y969000D03*
X777500Y351000D03*
X782500D03*
X776468Y447600D03*
X800000Y100000D03*
X800500Y977500D03*
X794500D03*
X800500Y982000D03*
X794500D03*
X810000Y120000D03*
X818500Y361600D03*
X813500Y367000D03*
X820500Y754000D03*
Y765500D03*
X828500Y361500D03*
X837000D03*
X846500Y362000D03*
X842000Y367000D03*
Y372000D03*
Y377500D03*
X870000Y160000D03*
X884000Y396500D03*
X879500D03*
X895000Y96000D03*
X899500Y92500D03*
X890000Y140000D03*
X899000Y405500D03*
X894000D03*
X899000Y410500D03*
X894000D03*
X910000Y160000D03*
X915000Y805000D03*
Y825000D03*
Y845000D03*
Y865000D03*
Y885000D03*
Y905000D03*
Y925000D03*
Y945000D03*
Y965000D03*
X966000Y209500D03*
X961000Y212500D03*
X965000Y725500D03*
X980000D03*
X1004500Y84000D03*
X1007000Y12000D03*
X1013500Y84000D03*
X1009000D03*
X1020500Y882500D03*
Y887000D03*
X1032000Y82500D03*
Y90000D03*
Y97000D03*
X1035000Y970000D03*
X1051000Y883600D03*
Y888500D03*
X1058000Y889500D03*
Y902500D03*
Y896000D03*
X1055000Y970000D03*
X1084988Y154203D03*
X1085150Y158400D03*
X1075000Y970000D03*
X1100000Y180000D03*
X1102500Y762500D03*
X1097500D03*
X1102500Y767400D03*
X1097500D03*
X1093000Y766500D03*
X1097500Y797500D03*
X1105000Y400500D03*
X1114500Y855500D03*
X1119000D03*
X1105000Y970000D03*
X1125000D03*
X1137000Y890000D03*
X1144500D03*
X1152000D03*
X1145000Y970000D03*
X1158000Y890000D03*
X1164500D03*
X1170500Y461000D03*
X1175000Y970000D03*
X1188500Y500000D03*
X1195920Y753700D03*
X1195000Y970000D03*
X1216500Y710125D03*
X1215000Y970000D03*
X1249300Y166000D03*
X1240600Y167000D03*
X1240700Y171200D03*
X1240800Y179800D03*
X1240700Y175500D03*
Y184000D03*
X1246000Y263500D03*
X1324500Y345400D03*
Y341000D03*
X1329000Y341100D03*
Y345500D03*
X1323000Y368000D03*
X1327500D03*
X1332000D03*
Y372400D03*
X1327500D03*
X1323000D03*
X1338000Y341100D03*
X1333500D03*
Y345500D03*
X1338000D03*
X1360000Y631500D03*
X1355500Y631000D03*
X1358000Y626000D03*
X1357500Y635500D03*
G54D11*
X19272Y337795D03*
Y396850D03*
X98838Y337795D03*
Y396850D03*
G54D20*
X1392657Y60039D03*
Y96260D03*
G54D21*
G01X319309Y89503D02*
Y87971D01*
X345780Y61500D01*
X366790D01*
X369489Y64199D01*
X375306D01*
X379269Y68162D01*
X498639D01*
X572627Y142150D01*
X687510D01*
X693360Y148000D01*
X802107D01*
X829107Y175000D01*
X961000D01*
X974500Y188500D01*
G01X357500Y75500D02*
X353388D01*
X337500Y91388D01*
Y92365D01*
X332365Y97500D01*
X328600D01*
X324200Y101900D01*
G01X357500Y79500D02*
X365360Y87360D01*
X465903D01*
X495890Y117347D01*
Y145926D01*
X499390Y149426D01*
Y153500D01*
G01X357500Y75500D02*
X366860Y84860D01*
X466939D01*
X498391Y116312D01*
Y144891D01*
X503000Y149500D01*
Y153000D01*
X503500Y153500D01*
G01X652714Y428214D02*
X657500Y433000D01*
Y444500D01*
X658500Y445500D01*
Y466944D01*
X667056Y475500D01*
G01X647500Y425500D02*
X650000Y428000D01*
Y434000D01*
X645500Y438500D01*
Y459500D01*
G01X691400Y231100D02*
X708700Y213800D01*
X728100D01*
G01X917000Y752500D02*
X917500Y752000D01*
X999980D01*
X1017480Y734500D01*
Y701980D01*
X984700Y669200D01*
Y548200D01*
X984650Y548150D01*
Y502949D01*
X992599Y495000D01*
X1020030D01*
X1021130Y496100D01*
X1022870D01*
X1023970Y495000D01*
X1040000D01*
X1076100Y458900D01*
X1093012D01*
X1094700Y460588D01*
Y461200D01*
X1098500Y465000D01*
G01X1088000Y461000D02*
X1049000Y500000D01*
X991135D01*
X987150Y503985D01*
Y544650D01*
X989000Y546500D01*
Y659500D01*
G01X1263000Y278500D02*
Y273511D01*
X1249489Y260000D01*
X1208500D01*
X1205500Y257000D01*
X1199612D01*
X1188912Y246300D01*
X1186700D01*
X1186000Y247000D01*
X1172500D01*
X1168000Y251500D01*
X1155000D01*
X1150500Y247000D01*
X1089484D01*
X1058000Y215516D01*
Y211000D01*
X1056500Y209500D01*
Y194000D01*
G01X1256000Y252000D02*
X1249500D01*
X1247318Y254182D01*
X1200330D01*
X1189948Y243800D01*
X1185200D01*
X1184500Y244500D01*
X1171000D01*
X1166500Y249000D01*
X1156500D01*
X1151500Y244000D01*
X1090020D01*
X1061000Y214980D01*
Y211500D01*
G01X1243000Y431500D02*
X1235500Y439000D01*
X1234500D01*
G01X1330500Y441000D02*
X1311000D01*
X1281000Y411000D01*
Y405050D01*
X1280500Y404550D01*
G01X1294600Y524200D02*
Y480265D01*
X1298000Y476865D01*
Y476500D01*
X1299800Y474700D01*
Y474088D01*
X1301088Y472800D01*
X1301700D01*
X1311000Y463500D01*
G54D12*
X8442Y847311D03*
X50395Y384679D03*
X40945Y384710D03*
X48820Y412435D03*
X39370Y412673D03*
X40054Y823970D03*
X36004Y839500D03*
X52000Y872720D03*
X38804Y906220D03*
X41500Y941500D03*
X46500Y944500D03*
X59840Y384679D03*
X67715Y412518D03*
X58270Y412485D03*
X60304Y663220D03*
X64304Y698720D03*
X63304Y706720D03*
X64272Y736004D03*
X59272Y790504D03*
X57772Y801504D03*
X61492Y803004D03*
X66022Y827254D03*
X65804Y835720D03*
X57804Y834720D03*
X61804D03*
X55304Y849720D03*
X52304Y868220D03*
X78740Y384915D03*
X69290Y384865D03*
X77165Y412590D03*
X76804Y662720D03*
X73804Y699720D03*
X81304Y710220D03*
X77272Y724004D03*
X75432Y758844D03*
X76272Y762504D03*
X77804Y773720D03*
X71804Y789720D03*
X84804Y808720D03*
X73772Y822004D03*
X79000Y836500D03*
X69804Y835720D03*
X77500Y832000D03*
X83838Y848133D03*
X76804Y847720D03*
X81304Y884470D03*
X81804Y888720D03*
X72770Y906488D03*
X95304Y663720D03*
X97737Y698653D03*
X96060Y762476D03*
X86404Y774720D03*
X100804D03*
X99804Y799720D03*
X85804Y816220D03*
X92304Y835720D03*
X87804D03*
X87928Y848107D03*
X98304Y888220D03*
X97804Y940720D03*
X112654Y314453D03*
X111304Y663720D03*
X111907Y698617D03*
X115804Y798720D03*
X105000Y834500D03*
X110500Y848500D03*
X115500D03*
X101804Y940720D03*
X132500Y312500D03*
X124500Y316000D03*
X127301Y354709D03*
X131147D03*
X132500Y547000D03*
Y559600D03*
Y556000D03*
Y551500D03*
X133500Y582500D03*
X125050Y583000D03*
X126500Y587500D03*
X121685Y587919D03*
X134000Y587000D03*
X132804Y894220D03*
X143147Y354709D03*
X139301D03*
X135500Y511000D03*
X136000Y566000D03*
X136500Y576900D03*
Y573300D03*
Y580500D03*
Y569700D03*
X140500Y568000D03*
X144000Y572500D03*
X149100Y661100D03*
X143010Y676400D03*
X162595Y296709D03*
X153437Y320458D03*
X155874Y310209D03*
X152995Y329119D03*
X159674Y328609D03*
X159774Y320709D03*
X164147Y328699D03*
X155147Y354709D03*
X162801D03*
X166647D03*
X151301D03*
X160500Y586500D03*
X156900D03*
X152948Y587000D03*
X166875Y678285D03*
X153500Y690275D03*
X163000Y901000D03*
X158000D03*
X172285Y296964D03*
X181889Y297303D03*
X171295Y320709D03*
X180315Y321209D03*
X167993Y328699D03*
X179622Y328749D03*
X175776D03*
X167469Y588969D03*
X172040Y688960D03*
X179500Y847000D03*
X181000Y901000D03*
X174500Y901500D03*
X168500Y901000D03*
X197245Y296571D03*
X196063Y319209D03*
X192874Y326209D03*
X198864Y323297D03*
X198500Y563000D03*
X198000Y785000D03*
X186000Y841500D03*
X185000Y856000D03*
X185500Y848260D03*
X187000Y878000D03*
X190500Y894000D03*
X195000Y891500D03*
X188000Y901000D03*
X197000D03*
X207086Y297418D03*
X205511Y320709D03*
X214960Y321044D03*
X208338Y323297D03*
X202710D03*
X212134D03*
X203000Y564500D03*
X212500Y786000D03*
X205500Y830000D03*
X203500Y894000D03*
X208000Y892000D03*
X205500Y901000D03*
X217295Y296709D03*
X216500Y516000D03*
X227000Y858000D03*
X217000Y858500D03*
X222000Y853500D03*
Y858500D03*
Y863500D03*
Y893600D03*
X243755Y490890D03*
X237953Y861453D03*
X252000Y846500D03*
X252500Y851500D03*
X253610Y863447D03*
X269000Y921500D03*
X274000D03*
X296200Y94400D03*
X314000Y102500D03*
X302000Y94300D03*
X305429Y219400D03*
Y223000D03*
X307500Y299000D03*
X324500Y6000D03*
Y10500D03*
X319309Y89503D03*
X317500Y101000D03*
X324200Y101900D03*
X329929Y241500D03*
X326000Y292500D03*
X329055Y569500D03*
X336700Y4300D03*
X341200D03*
X346000Y4400D03*
X346404Y260000D03*
X339888Y586388D03*
X355000Y4400D03*
X350500D03*
X360400D03*
X357500Y79500D03*
Y75500D03*
X364000Y869500D03*
X364900Y4400D03*
X369400D03*
X377855Y300110D03*
X374000Y293500D03*
X371710Y406535D03*
X370575Y409952D03*
X380000Y872000D03*
X371938Y922438D03*
X381500Y297000D03*
X395104Y291056D03*
X386055Y454500D03*
X396000Y714500D03*
X392500Y718500D03*
X395500Y867000D03*
X408656Y291500D03*
X405555Y293500D03*
X410500Y885500D03*
X401500Y994500D03*
X416187Y294711D03*
X425178Y798000D03*
X418278Y828000D03*
Y840000D03*
X418500Y857500D03*
X418278Y854000D03*
Y846500D03*
X425000Y994500D03*
X440000Y5000D03*
X432500Y301000D03*
X432178Y798000D03*
X438178Y798500D03*
X444678Y798400D03*
X431500Y886000D03*
X437678D03*
X443178D03*
X432000Y933500D03*
X460000Y5000D03*
X458429Y175590D03*
X456178Y798000D03*
X452978Y805400D03*
X451178Y886000D03*
X460678D03*
X457578Y879700D03*
X469000Y113000D03*
X472990Y113350D03*
X462700Y120800D03*
X463371Y290371D03*
X475678Y798500D03*
X463178D03*
X469178D03*
X468178Y886000D03*
X472178D03*
X485000Y5000D03*
X488500Y114200D03*
X482178Y886000D03*
X499390Y153500D03*
X503500D03*
X495929Y164500D03*
X497778Y843000D03*
Y838500D03*
Y847000D03*
X498500Y867500D03*
X515000Y5000D03*
X513200Y121450D03*
X513000Y156500D03*
X519706Y314000D03*
X515860D03*
X527002Y319359D03*
X523348D03*
X526500Y346532D03*
Y342969D03*
Y352969D03*
X520500Y351500D03*
Y347937D03*
Y358937D03*
X526500Y356532D03*
X520500Y362500D03*
X528500Y172000D03*
X539714Y179150D03*
X542500Y188500D03*
X537479Y197875D03*
X534960Y321000D03*
X538614D03*
X529848Y325500D03*
X533502D03*
X545000Y5000D03*
X550500Y188000D03*
X560500Y186000D03*
X555500Y194000D03*
X559500D03*
X545000Y195000D03*
X549926Y204000D03*
X575000Y5000D03*
X577000Y58000D03*
X572000Y189000D03*
X571398Y183602D03*
X561429Y174441D03*
X575500Y198400D03*
X576650Y204500D03*
X563100Y194000D03*
X563704Y272000D03*
X563555Y333000D03*
X564215Y369339D03*
X566430Y366500D03*
X587175Y202525D03*
X591413Y199087D03*
X583500Y204500D03*
X585325Y198000D03*
X583325Y208500D03*
X583204Y236805D03*
X642800Y433587D03*
X641625Y465375D03*
X635325Y457500D03*
X628250Y570200D03*
X646500Y101000D03*
X650500D03*
X652714Y428214D03*
X647500Y425500D03*
X645500Y459500D03*
X656162Y472338D03*
X654500Y494000D03*
X647252Y576500D03*
X662248Y101000D03*
X667748Y104000D03*
X663500Y452000D03*
X672500D03*
X660000Y443500D03*
X663500Y456000D03*
Y460500D03*
X667500Y454000D03*
Y458500D03*
X672500Y456000D03*
Y460500D03*
X667056Y475500D03*
X685000Y5000D03*
X681000Y452000D03*
Y456000D03*
Y460500D03*
X676500Y454000D03*
Y458500D03*
X690000Y460500D03*
X687968Y755284D03*
Y781784D03*
X695000Y20000D03*
X700000Y60500D03*
X705900Y569200D03*
X698818Y759350D03*
X703328Y800144D03*
X697250Y876750D03*
X715000Y5000D03*
X725000Y20000D03*
X715716Y82652D03*
X713716Y121284D03*
X721716Y112784D03*
Y116784D03*
X717716Y121284D03*
X721716D03*
Y129284D03*
Y125284D03*
X711500Y179400D03*
X723168Y774984D03*
X712500Y859750D03*
X716250Y860250D03*
X728966Y53966D03*
Y65466D03*
X729716Y121284D03*
X725716D03*
X728100Y213800D03*
X732500Y485500D03*
X734500Y547500D03*
X734462Y553538D03*
X733268Y757984D03*
X735000Y780500D03*
X727468Y819284D03*
X733440Y875560D03*
X745000Y5000D03*
X755000Y20000D03*
X747800Y50200D03*
X757200Y103100D03*
X745500Y145000D03*
X749750Y454000D03*
X755300Y489300D03*
X746750Y571750D03*
X748000Y579500D03*
X745400Y877600D03*
X762250Y71000D03*
X761000Y88500D03*
Y82500D03*
X760600Y94500D03*
X770500Y136000D03*
X770900Y144300D03*
X771000Y464000D03*
X765009Y563491D03*
X760125Y666875D03*
X770646Y685354D03*
X775000Y5000D03*
X785000Y20000D03*
X788600Y449300D03*
X784800D03*
X784900Y453000D03*
X788800D03*
X784274Y486274D03*
X790600Y547600D03*
X790000Y554500D03*
X785500Y666500D03*
X783746Y692754D03*
X787500Y783500D03*
X782750Y845750D03*
X781000Y877000D03*
X776750Y964750D03*
X805000Y5000D03*
X796000Y167600D03*
X795500Y163408D03*
X806274Y434726D03*
X791000Y562000D03*
X802500Y579500D03*
X794000Y723500D03*
X791500Y783500D03*
X805250Y865750D03*
X794500Y897000D03*
X815000Y20000D03*
X811000Y430500D03*
X810000Y735500D03*
X814000Y849500D03*
X819000Y868500D03*
X810000Y980000D03*
X835000Y5000D03*
X825500Y411100D03*
X832500Y404000D03*
X826500Y436000D03*
X826000Y465078D03*
X831000Y598500D03*
X839250Y854500D03*
X826060Y863440D03*
X824560Y868560D03*
X840000Y980000D03*
X850000Y20000D03*
X852000Y401500D03*
X842000D03*
X847000Y396500D03*
Y401500D03*
Y406500D03*
X854000Y436500D03*
X846250Y642250D03*
X854000Y640500D03*
X852500Y710500D03*
X842500Y719500D03*
X852600Y868500D03*
X865000Y5000D03*
X872000Y75500D03*
X863820Y363880D03*
X868820D03*
X871500Y484000D03*
X871000Y639500D03*
X870500Y665060D03*
X861250Y649250D03*
X865500Y690500D03*
X860500Y734000D03*
X870000Y980000D03*
X880000Y20000D03*
X877000Y409500D03*
X886300Y443100D03*
X882700D03*
X874450Y463500D03*
X877500Y612500D03*
X884200Y636500D03*
X878500Y695500D03*
X895000Y5000D03*
X904600Y406600D03*
X893600Y443100D03*
X889900D03*
X900000Y980000D03*
X910000Y20000D03*
X917000Y752500D03*
X925000Y5000D03*
X936000Y373500D03*
X934000Y448700D03*
X955000Y5000D03*
X940000Y20000D03*
X970000D03*
X958500Y187500D03*
X957990Y191064D03*
X962000Y251500D03*
X965500Y260500D03*
X963500Y256000D03*
X959500Y351688D03*
X964000Y354000D03*
X968085Y452065D03*
X970750Y703000D03*
X985000Y5000D03*
X980078Y204578D03*
X980960Y195257D03*
X975000Y701000D03*
X1000000Y20000D03*
X989000Y66500D03*
X996500Y167000D03*
X988660Y190500D03*
X992690Y466750D03*
X996910Y466560D03*
X992000Y505500D03*
X989000Y659500D03*
X1015000Y5000D03*
X1012000Y43000D03*
X1020500Y124500D03*
X1017274Y219274D03*
X1007500Y507000D03*
X1007032Y879968D03*
X1011966Y893534D03*
X1020282Y911218D03*
X1010000Y980000D03*
X1036019Y203177D03*
X1036000Y199500D03*
X1035922Y209578D03*
X1025500Y657000D03*
X1023500Y727000D03*
X1037000Y734000D03*
X1035000Y800000D03*
Y804500D03*
X1021468Y866968D03*
X1032600Y867657D03*
X1031500Y884500D03*
X1035216Y884468D03*
X1035000Y888500D03*
Y880500D03*
X1045000Y5000D03*
X1045968Y185500D03*
X1038000Y604000D03*
X1053500Y620500D03*
X1038000Y635000D03*
X1042450Y648500D03*
X1045500Y639500D03*
X1050092Y655052D03*
X1038500Y706500D03*
X1040208Y745020D03*
X1052500Y773350D03*
X1044000Y763940D03*
X1039000Y884500D03*
X1042500Y930000D03*
X1040000Y980000D03*
X1060000Y20000D03*
X1056500Y194000D03*
X1061000Y211500D03*
X1068300Y488700D03*
X1059000Y558190D03*
X1058000Y599500D03*
X1056000Y604000D03*
X1058500Y660900D03*
X1054900D03*
X1058350Y681450D03*
X1068500Y677000D03*
Y687000D03*
X1066000Y717000D03*
X1059800Y719740D03*
X1054000Y735000D03*
X1056350Y748000D03*
X1063000Y780000D03*
X1075000Y5000D03*
X1071000Y71000D03*
X1077250Y102000D03*
X1077500Y97000D03*
Y107500D03*
X1086000Y126500D03*
X1081000Y548000D03*
Y544400D03*
X1084599Y544520D03*
X1086000Y556000D03*
X1071500Y589000D03*
X1085000Y661000D03*
X1074500Y694754D03*
X1074426Y687255D03*
X1074389Y691155D03*
X1074000Y699500D03*
X1074148Y711624D03*
X1074600Y707724D03*
X1074000Y703500D03*
X1073384Y722384D03*
X1073000Y730834D03*
Y726444D03*
X1074288Y715534D03*
X1077500Y745374D03*
X1072000Y743500D03*
X1070098Y764500D03*
X1083700Y835725D03*
X1085468Y895968D03*
X1077000Y943075D03*
X1083200Y956500D03*
X1070000Y980000D03*
X1090000Y20000D03*
X1088000Y85500D03*
X1098000Y126500D03*
X1092500Y461500D03*
X1098500Y465000D03*
X1100575Y559075D03*
X1098000Y562000D03*
X1091425Y551425D03*
X1091000Y692519D03*
X1090257Y724253D03*
X1087600Y727029D03*
X1094853Y726853D03*
X1095500Y812000D03*
X1097500Y849000D03*
X1089000Y867284D03*
X1093468Y896968D03*
X1100000Y980000D03*
X1105000Y5000D03*
Y15000D03*
Y75000D03*
Y105000D03*
Y135000D03*
X1111500Y517500D03*
X1107500Y580000D03*
X1113500Y824500D03*
X1118034Y847034D03*
X1116468Y870284D03*
Y874284D03*
Y865784D03*
X1112468Y870284D03*
X1114500Y886000D03*
X1103000Y888300D03*
X1118500Y886000D03*
X1130000Y361500D03*
X1124327Y465391D03*
X1132000Y562000D03*
X1125600Y570600D03*
X1120500Y729500D03*
X1124000Y729000D03*
X1121000Y823500D03*
X1135468Y854032D03*
X1120468Y870284D03*
X1131275Y867725D03*
X1130000Y980000D03*
X1150640Y359860D03*
X1146640D03*
X1142640D03*
X1136075Y559075D03*
X1156100Y316405D03*
Y312795D03*
X1165000Y308175D03*
Y304565D03*
X1161530Y360430D03*
X1157480Y361620D03*
X1160058Y364558D03*
X1164000Y397000D03*
X1166500Y415500D03*
X1161000Y541500D03*
X1153500Y784190D03*
X1162000Y960625D03*
X1155000Y980000D03*
X1181427Y251500D03*
X1180677Y256500D03*
X1173777Y290125D03*
X1169777D03*
X1173125Y323716D03*
X1169515D03*
X1174500Y366000D03*
X1175125Y370000D03*
X1174500Y404000D03*
X1173500Y422500D03*
X1169075Y613500D03*
X1188000Y248500D03*
X1192743Y289800D03*
X1188877D03*
X1199685Y344588D03*
X1196075D03*
X1191000Y528000D03*
X1189000Y533825D03*
X1194564Y530936D03*
X1185500Y548075D03*
X1200500Y547925D03*
X1196000Y605800D03*
X1184956Y619272D03*
X1199551Y683968D03*
X1195937Y683849D03*
X1189890Y684053D03*
X1192937Y683911D03*
X1194000Y764500D03*
X1196000Y847500D03*
X1188875Y856625D03*
X1196000Y874500D03*
X1185000Y980000D03*
X1211500Y5500D03*
Y35500D03*
Y65500D03*
Y85500D03*
Y107500D03*
Y137500D03*
X1216000Y390000D03*
X1209500Y404500D03*
X1216500Y439500D03*
X1210000Y507500D03*
X1201500Y535000D03*
X1208500Y623000D03*
X1203181Y683968D03*
X1206781Y684003D03*
X1216000Y702500D03*
X1206500Y757000D03*
X1213500Y756000D03*
X1211000Y847500D03*
X1204000Y862000D03*
X1217250Y862250D03*
X1208940Y874560D03*
X1211500Y882500D03*
X1215000Y980000D03*
X1229500Y533000D03*
X1231632Y537000D03*
X1221500Y539500D03*
X1233000Y554502D03*
X1231450Y677500D03*
X1229000Y726500D03*
X1233000Y782500D03*
X1223000Y826500D03*
X1218500Y834500D03*
X1229807Y847000D03*
X1235500Y5000D03*
X1243000Y431500D03*
X1234500Y439000D03*
X1242000Y459000D03*
X1246750Y476250D03*
X1249000Y509500D03*
X1235482Y546982D03*
X1240000Y546500D03*
Y542900D03*
X1240173Y550327D03*
X1250500Y567000D03*
X1241000Y631500D03*
X1237500Y675500D03*
X1235000Y682000D03*
X1240660Y829000D03*
X1235258Y820758D03*
X1245000Y980000D03*
X1264177Y233500D03*
X1256000Y252000D03*
X1262558Y254942D03*
X1261677Y241500D03*
Y245500D03*
X1264500Y260000D03*
X1263000Y278500D03*
X1250677Y287500D03*
Y283500D03*
X1260577Y299968D03*
Y296102D03*
X1253477Y312800D03*
X1253577Y308800D03*
X1253177Y320500D03*
Y324500D03*
X1253000Y511000D03*
X1260500Y546400D03*
X1263500Y550000D03*
X1257100Y664300D03*
X1266000Y665600D03*
X1262500Y699825D03*
X1268000Y5000D03*
X1276500Y234000D03*
X1267677Y232500D03*
X1280500Y404550D03*
X1280000Y420500D03*
X1272500Y466600D03*
X1279340Y618660D03*
X1281500Y713000D03*
X1275000Y980000D03*
X1293960Y528740D03*
X1294600Y524200D03*
X1284825Y621500D03*
X1294000Y628000D03*
X1299000Y641500D03*
X1296000Y638500D03*
X1290500Y635500D03*
X1298034Y907034D03*
X1307500Y5000D03*
X1306000Y334500D03*
Y338500D03*
X1311000Y463500D03*
X1304700Y536000D03*
X1302500Y559500D03*
X1310500Y625000D03*
X1310425Y660062D03*
X1311100Y656400D03*
X1312500Y838000D03*
X1303750Y862250D03*
X1307468Y884532D03*
X1300000Y980000D03*
X1330500Y441000D03*
X1325250Y834250D03*
X1316500Y839000D03*
X1317000Y850500D03*
X1318113Y846371D03*
X1321466Y907034D03*
X1330000Y980000D03*
X1337500Y5000D03*
X1339500Y305500D03*
X1341873Y344873D03*
X1335317Y575412D03*
X1342648Y612412D03*
X1347617Y610412D03*
X1334500Y669000D03*
X1352000Y85500D03*
X1350084Y296500D03*
X1356817Y579012D03*
X1364617Y592912D03*
X1360200Y614800D03*
X1353517Y627512D03*
X1357300Y617700D03*
X1360000Y980000D03*
X1379500Y314000D03*
X1367617Y570012D03*
X1394122Y5878D03*
X1390004Y122600D03*
G54D22*
G01X178000Y590000D02*
X180500Y592500D01*
X480000D01*
X516500Y556000D01*
G54D13*
G01X-245081Y-422119D02*
G02I-12000J0D01*
G01X-250231D02*
G02I-6850J0D01*
G01X-241081D02*
X-273081D01*
G01X-257081Y-438119D02*
Y-406119D01*
G01X-241081Y-438119D02*
Y-518119D01*
G01D02*
X1034819D01*
G01X-241081Y-473619D02*
X1034819D01*
G01X-241081Y-438119D02*
X1034819D01*
G01X12120Y337795D02*
X19272D01*
G01X12120Y396850D02*
X19272D01*
G01Y330643D02*
Y337795D01*
G01D02*
Y344947D01*
G01Y337795D02*
X26424D01*
G01X19272Y389698D02*
Y396850D01*
G01D02*
Y404002D01*
G01Y396850D02*
X26424D01*
G01X59272Y790504D02*
X63488D01*
X81704Y808720D01*
X84804D01*
G01X59272Y790504D02*
X54604Y795172D01*
Y821140D01*
X65804Y832340D01*
Y835720D01*
G01X77272Y724004D02*
X72732Y728544D01*
Y746148D01*
X75432Y748848D01*
Y758844D01*
G01X98838Y330643D02*
Y337795D01*
G01D02*
Y344947D01*
G01X91686Y337795D02*
X98838D01*
G01D02*
X105990D01*
G01X98838Y389698D02*
Y396850D01*
G01D02*
Y404002D01*
G01X91686Y396850D02*
X98838D01*
G01D02*
X105990D01*
G01X355500Y608500D02*
X344500Y597500D01*
X127376D01*
X118600Y588724D01*
Y583200D01*
X121000Y580800D01*
Y545500D01*
G01X153937Y235196D02*
Y238898D01*
G01Y243070D02*
Y246772D01*
G01D02*
Y250474D01*
G01X150235Y246772D02*
X153937D01*
G01D02*
X157639D01*
G01X153937Y238898D02*
Y242600D01*
G01X150235Y238898D02*
X153937D01*
G01D02*
X157639D01*
G01X153937Y256849D02*
Y260551D01*
G01D02*
Y264253D01*
G01X150235Y260551D02*
X153937D01*
G01D02*
X157639D01*
G01X166200Y506500D02*
Y492200D01*
X172000Y486400D01*
G01X190118Y734957D02*
Y739409D01*
G01D02*
Y743861D01*
G01X185666Y739409D02*
X190118D01*
G01D02*
X194570D01*
G01X195666D02*
X200118D01*
G01X215666D02*
X220118D01*
G01X210118Y734957D02*
Y739409D01*
G01D02*
Y743861D01*
G01X205666Y739409D02*
X210118D01*
G01D02*
X214570D01*
G01X200118Y734957D02*
Y739409D01*
G01D02*
Y743861D01*
G01Y739409D02*
X204570D01*
G01X224015Y234961D02*
Y238663D01*
G01X220313Y234961D02*
X224015D01*
G01D02*
X227717D01*
G01X224015Y243070D02*
Y246772D01*
G01D02*
Y250474D01*
G01X220313Y246772D02*
X224015D01*
G01D02*
X227717D01*
G01X224015Y256849D02*
Y260551D01*
G01D02*
Y264253D01*
G01X220313Y260551D02*
X224015D01*
G01D02*
X227717D01*
G01X230118Y724957D02*
Y729409D01*
G01D02*
Y733861D01*
G01X225666Y729409D02*
X230118D01*
G01D02*
X234570D01*
G01X220118Y734957D02*
Y739409D01*
G01D02*
Y743861D01*
G01Y739409D02*
X224570D01*
G01X230118Y734957D02*
Y739409D01*
G01D02*
Y743861D01*
G01X225666Y739409D02*
X230118D01*
G01D02*
X234570D01*
G01X247319Y-438119D02*
Y-518119D01*
G01X240118Y734957D02*
Y739409D01*
G01D02*
Y743861D01*
G01X235666Y739409D02*
X240118D01*
G01D02*
X244570D01*
G01X245666D02*
X250118D01*
G01X260118Y724957D02*
Y729409D01*
G01D02*
Y733861D01*
G01X255666Y729409D02*
X260118D01*
G01D02*
X264570D01*
G01X260118Y734957D02*
Y739409D01*
G01D02*
Y743861D01*
G01X255666Y739409D02*
X260118D01*
G01D02*
X264570D01*
G01X250118Y734957D02*
Y739409D01*
G01D02*
Y743861D01*
G01Y739409D02*
X254570D01*
G01X270118Y724957D02*
Y729409D01*
G01D02*
Y733861D01*
G01X265666Y729409D02*
X270118D01*
G01D02*
X274570D01*
G01X270118Y734957D02*
Y739409D01*
G01D02*
Y743861D01*
G01X265666Y739409D02*
X270118D01*
G01D02*
X274570D01*
G01X471480Y105660D02*
X471190Y105370D01*
X468299D01*
X465889Y102960D01*
X426000D01*
X420460Y108500D01*
X319500D01*
X314000Y103000D01*
Y102500D01*
G01X488500Y114200D02*
X468190Y93890D01*
X426610D01*
X414944Y105556D01*
X349056D01*
X348500Y105000D01*
X321500D01*
X317500Y101000D01*
G01X370500Y72100D02*
X376900Y78500D01*
X469500D01*
X508950Y117950D01*
X523950D01*
X556500Y150500D01*
X685000D01*
G01X384819Y-438119D02*
Y-518119D01*
G01X499819Y-438119D02*
Y-518119D01*
G01X513200Y121450D02*
Y121800D01*
X511929Y123071D01*
Y154829D01*
X513300Y156200D01*
X513000Y156500D01*
G01X642800Y433587D02*
Y379043D01*
X634000Y370243D01*
Y367757D01*
X631743Y365500D01*
X586881D01*
X563654Y342273D01*
X563000Y340965D01*
Y333555D01*
X563555Y333000D01*
G01X585315Y38832D02*
Y44134D01*
G01D02*
Y49436D01*
G01X580013Y44134D02*
X585315D01*
G01D02*
X590617D01*
G01X635325Y457500D02*
X628000Y450175D01*
Y371000D01*
X630500Y368500D01*
G01X654527Y38832D02*
Y44134D01*
G01D02*
Y49436D01*
G01X649225Y44134D02*
X654527D01*
G01D02*
X659829D01*
G01X667319Y-438119D02*
Y-518119D01*
G01X710100Y182700D02*
X710200Y182600D01*
X730600D01*
X792000Y244000D01*
X915500D01*
X934700Y263200D01*
X1095800D01*
X1097200Y261800D01*
X1159300D01*
X1160500Y263000D01*
X1185858D01*
X1188358Y265500D01*
X1204500D01*
X1207000Y263000D01*
X1245500D01*
X1246000Y263500D01*
G01X837319Y-438119D02*
Y-518119D01*
G01X1034819Y-438119D02*
Y-518119D01*
G01X1066819Y-422119D02*
X1034819D01*
G01X1050819Y-438119D02*
Y-406119D01*
G01X1062819Y-422119D02*
G02I-12000J0D01*
G01X1057669D02*
G02I-6850J0D01*
G01X1084646Y39165D02*
Y43267D01*
G01D02*
Y47369D01*
G01X1080544Y43267D02*
X1084646D01*
G01D02*
X1088748D01*
G01X1173500Y422500D02*
Y405000D01*
X1174500Y404000D01*
G01X1170500Y461000D02*
X1173500Y458000D01*
Y422500D01*
G01X1216000Y702500D02*
X1210000D01*
X1209500Y703000D01*
X1189000D01*
X1184619Y698619D01*
X1182813D01*
G01X1310500Y625000D02*
X1308781D01*
X1287875Y604094D01*
Y599556D01*
X1271769Y583450D01*
X1257081D01*
X1220807Y547176D01*
X1206357D01*
X1188250Y529069D01*
Y500250D01*
X1188500Y500000D01*
G01X1211000Y847500D02*
X1196000D01*
G01X1208940Y874560D02*
X1196060D01*
X1196000Y874500D01*
G01X1216000Y390000D02*
Y393000D01*
X1215000Y394000D01*
Y421500D01*
X1217500Y424000D01*
Y438000D01*
X1216500Y439000D01*
Y439500D01*
G01X1216000Y702500D02*
Y702501D01*
X1222999Y709500D01*
X1252825D01*
X1262500Y699825D01*
G01X1208940Y874560D02*
X1211000Y872500D01*
Y847500D01*
G01X1233000Y782500D02*
X1234893Y780607D01*
Y762804D01*
X1270697Y727000D01*
X1272500D01*
X1281500Y718000D01*
Y713000D01*
G01X1240660Y829000D02*
Y817660D01*
X1233000Y810000D01*
Y782500D01*
G01X1242000Y459000D02*
Y471500D01*
X1246750Y476250D01*
G01X1272500Y466600D02*
X1264900Y459000D01*
X1242000D01*
G01X1249000Y509500D02*
X1246551Y511949D01*
Y563051D01*
X1250500Y567000D01*
G01X1302500Y559500D02*
X1293000Y550000D01*
X1263500D01*
G01X1392657Y55837D02*
Y60039D01*
G01D02*
Y64241D01*
G01X1388455Y60039D02*
X1392657D01*
G01Y92058D02*
Y96260D01*
G01D02*
Y100462D01*
G01X1388455Y96260D02*
X1392657D01*
X112900Y988500D03*
X124500Y515500D03*
X166200Y506500D03*
X172000Y486400D03*
X311500Y153000D03*
X299000Y148000D03*
X307129Y143000D03*
X305029Y147700D03*
X304300Y160200D03*
X304100Y167000D03*
X311300D03*
X312500Y159100D03*
X319014Y152977D03*
X328700Y154400D03*
X328629Y146800D03*
X330400Y141600D03*
X318200Y159100D03*
X334000Y147600D03*
X368296Y136246D03*
X371456Y136221D03*
X368305Y139401D03*
X368333Y148827D03*
X368329Y151956D03*
X371493Y145667D03*
X368314Y142505D03*
Y145680D03*
X365187Y186605D03*
X368307Y205511D03*
Y199211D03*
X368336Y192904D03*
X377756Y211810D03*
X371457D03*
X393528Y167702D03*
X393542Y186614D03*
X393490Y174039D03*
X393541Y180315D03*
X384036Y189747D03*
X393519Y192900D03*
X387209Y192930D03*
X384055Y211810D03*
X387515Y365500D03*
X396500Y910500D03*
X399827Y167702D03*
X406140Y167716D03*
X406127Y161404D03*
X412427D03*
X412426Y167703D03*
X399841Y186614D03*
X399840Y180315D03*
X399790Y174039D03*
X406126Y174003D03*
X406139Y180315D03*
X406101Y186613D03*
X412426Y174003D03*
X412439Y186614D03*
X412400Y180314D03*
X406128Y192901D03*
X399791Y192938D03*
X412428Y192901D03*
X399803Y211810D03*
X406102D03*
X412794Y337991D03*
X421851Y142520D03*
X415552D03*
X428151D03*
X418726Y167703D03*
Y174003D03*
Y180303D03*
X418701Y186614D03*
X418727Y192902D03*
X428150Y211810D03*
X415551D03*
X421850D03*
X420500Y234500D03*
X427965Y318293D03*
X419913Y318051D03*
X417650Y316400D03*
X416482Y319022D03*
X424555Y318000D03*
X424023Y320783D03*
X424605Y330117D03*
X416950Y321783D03*
X428542Y341928D03*
Y337991D03*
X424605Y349802D03*
Y341928D03*
X428542Y389174D03*
X419500Y914000D03*
X437598Y148818D03*
Y155118D03*
X434450Y142520D03*
X437598Y180314D03*
Y186614D03*
X443879Y180320D03*
X437598Y205511D03*
Y199212D03*
Y192913D03*
X443897Y205512D03*
Y202363D03*
X437598Y211810D03*
X443897Y211811D03*
Y208662D03*
X436529Y229500D03*
X443113Y226339D03*
X439980Y232126D03*
X441379Y229700D03*
X437112Y232239D03*
X438500Y250000D03*
X431023Y317283D03*
X444555Y334000D03*
X441335Y321000D03*
X440353Y345865D03*
X444290Y369487D03*
X436416D03*
X440353Y357676D03*
X444290Y353739D03*
X440353Y365550D03*
X436416Y353739D03*
Y361613D03*
X444290Y381300D03*
X440353Y377363D03*
X436416Y381300D03*
X444290Y389174D03*
X436416D03*
X454329Y199800D03*
X456479Y202400D03*
X455929Y192800D03*
X456229Y196700D03*
X453829Y215600D03*
X453729Y219300D03*
X452393Y210236D03*
X457798Y217769D03*
X457729Y206800D03*
X448840Y225775D03*
X455429Y227500D03*
X451929Y229800D03*
X456929Y224507D03*
X456055Y338000D03*
X452055D03*
X452165Y349470D03*
X456103Y369487D03*
Y353739D03*
Y361613D03*
X460040Y357676D03*
Y365550D03*
X448227D03*
Y357676D03*
X460040Y385237D03*
X456103Y381300D03*
X460040Y377363D03*
X448227Y385237D03*
Y377363D03*
X456103Y389174D03*
X471480Y105660D03*
X466464Y151000D03*
X464570Y215750D03*
X463977Y369487D03*
Y361613D03*
Y381300D03*
Y389174D03*
X487599Y337991D03*
X483662D03*
Y341928D03*
X487599D03*
X483662Y345865D03*
X487599Y349802D03*
X483662D03*
X487599Y345865D03*
X533441Y211775D03*
X604500Y227500D03*
Y223000D03*
X691400Y231100D03*
X710100Y182700D03*
X720500Y478750D03*
X723000Y996500D03*
X731498D03*
X739368Y996610D03*
X727558Y996500D03*
X866112Y85626D03*
X902000Y63000D03*
X935000Y51500D03*
X937000Y63000D03*
X959900Y180700D03*
X974500Y188500D03*
X975007Y194300D03*
X1002500Y653000D03*
X1001100Y776500D03*
X1062940Y629945D03*
X1089500Y405000D03*
X1088000Y461000D03*
X1132417Y711189D03*
X1132459Y717481D03*
X1123500Y832470D03*
X1135500Y835000D03*
X1141954Y676581D03*
X1139858Y692074D03*
X1139000Y685667D03*
X1151307Y714306D03*
X1135589Y701714D03*
X1151352Y711178D03*
X1151318Y717518D03*
X1150734Y736950D03*
X1149470Y734451D03*
X1151564Y776924D03*
X1146200Y766300D03*
X1145270Y792670D03*
X1141700Y785113D03*
X1151590Y792660D03*
X1167048Y714312D03*
X1154434Y714335D03*
X1157581Y714331D03*
X1163905Y711206D03*
X1157636Y711200D03*
X1167000Y727500D03*
X1157637Y717463D03*
X1157643Y720642D03*
X1154430Y717481D03*
X1167049Y717501D03*
X1167048Y720612D03*
X1163898Y717462D03*
Y720612D03*
X1157112Y731702D03*
X1157000Y734500D03*
X1167002Y767508D03*
X1167326Y776936D03*
X1153219Y781303D03*
X1161545Y788844D03*
X1162693Y780865D03*
X1158092Y787715D03*
X1154712Y792690D03*
X1165492Y780957D03*
X1154200Y788900D03*
X1154700Y795790D03*
X1161022Y785693D03*
X1165063Y787500D03*
X1167410Y785530D03*
X1157990Y827000D03*
X1173389Y689121D03*
X1179678Y689111D03*
X1182817Y689155D03*
X1182796Y708013D03*
X1182813Y698619D03*
X1173350Y698590D03*
X1169282Y729708D03*
X1170199Y717501D03*
X1171500Y733725D03*
X1175000Y734870D03*
X1171108Y777368D03*
X1170911Y784912D03*
X1170718Y782118D03*
X1185965Y676573D03*
X1201250Y627000D03*
X1381415Y581195D03*
X1380925Y598315D03*
X1377996Y610847D03*
X1380925Y602035D03*
X1377996Y607382D03*
X1385135Y581195D03*
G54D23*
G01X77500Y832000D02*
X70768D01*
X66022Y827254D01*
G01X79000Y836500D02*
X76830Y838670D01*
X68582D01*
X65804Y835892D01*
Y835720D01*
G01X92304D02*
X88996Y839028D01*
X81528D01*
X79000Y836500D01*
G01X87928Y848107D02*
Y865596D01*
X81304Y872220D01*
Y884470D01*
G54D14*
X153937Y238898D03*
Y246772D03*
Y260551D03*
X224015Y234961D03*
Y246772D03*
Y260551D03*
G54D24*
G01X487599Y337991D02*
X491408D01*
G02X497830Y335331I0J-9082D01*
G01X503873Y329288D01*
G03X506983Y328000I3111J3112D01*
G01X539444D01*
G03X544837Y330234I0J7627D01*
G01X553051Y338448D01*
X553052D01*
X553772Y339168D01*
G03X559500Y353001I-13834J13831D01*
G01Y472000D01*
G02X560207Y473707I2414J0D01*
G01X580000Y493500D01*
G03X583500Y501950I-8452J8451D01*
G01Y573500D01*
G03X581379Y578621I-7243J0D01*
G01X491750Y668250D01*
G03X485594Y670800I-6156J-6156D01*
G01X194105D01*
G03X186244Y667544I1J-11119D01*
G01X175032Y656332D01*
G02X173264Y655600I-1768J1768D01*
G01X93444D01*
G03X86201Y652600I1J-10245D01*
G01X86200D01*
X71660Y638060D01*
Y638059D01*
X42350Y608749D01*
G03X38200Y598727I10022J-10020D01*
G01Y496001D01*
G03X43176Y483984I16993J-2D01*
G01X47580Y479580D01*
X115281Y411880D01*
G02X120700Y398797I-13083J-13083D01*
G01Y384364D01*
G03X125580Y372580I16665J-1D01*
G02X128699Y365050I-7530J-7530D01*
G01X128700Y358000D01*
G02X127362Y354770I-4568J0D01*
G01X127301Y354709D01*
G01X131147D02*
X131020D01*
G02X130291Y355196I0J789D01*
G01X130118Y355614D01*
G02X130000Y356209I1438J594D01*
G01Y365050D01*
G03X126500Y373500I-11950J0D01*
G02X122000Y384364I10864J10864D01*
G01Y398797D01*
G03X116200Y412800I-19802J1D01*
G01X44096Y484904D01*
G02X39500Y496000I11096J11096D01*
G01Y598728D01*
G02X43270Y607830I12872J0D01*
G01X72580Y637140D01*
G02X73524Y637454I778J-763D01*
G03X74468Y637769I165J1078D01*
G01X75316Y638617D01*
G03X75631Y639561I-763J779D01*
G02X75945Y640505I1077J166D01*
G01X76794Y641354D01*
G02X77738Y641669I779J-763D01*
G03X78682Y641983I166J1077D01*
G01X79530Y642832D01*
G03X79845Y643776I-762J779D01*
G02X80160Y644720I1078J165D01*
G01X81008Y645568D01*
G02X81952Y645883I779J-762D01*
G03X82896Y646198I165J1077D01*
G01X83745Y647046D01*
G03X84060Y647990I-763J779D01*
G02X84374Y648934I1077J166D01*
G01X87120Y651680D01*
G02X93445Y654300I6325J-6325D01*
G01X173268D01*
G03X175955Y655413I0J3800D01*
G01X187163Y666624D01*
G02X194106Y669500I6943J-6943D01*
G01X485593D01*
G02X490831Y667330I0J-7406D01*
G01X490830D01*
X580459Y577701D01*
G02X582200Y573499I-4201J-4202D01*
G01Y501951D01*
G02X579080Y494419I-10652J0D01*
G01X559580Y474919D01*
Y474920D01*
X559287Y474627D01*
G03X558200Y471999I2628J-2626D01*
G01Y353000D01*
G02X552852Y340088I-18261J0D01*
G01X543917Y331153D01*
G02X539443Y329300I-4474J4474D01*
G01X506984D01*
G02X504792Y330208I0J3100D01*
G01X498750Y336250D01*
G03X491408Y339291I-7342J-7342D01*
G01X489352D01*
G03X488365Y339700I-987J-987D01*
G01X486783D01*
G03X486300Y339500I0J-683D01*
G01X485590Y338789D01*
G02X483662Y337991I-1927J1928D01*
G01X487599Y341928D02*
G03X487886Y342047I0J406D01*
G01X488919Y343080D01*
G02X490529Y343747I1610J-1610D01*
G01X496000D01*
G02X499265Y342394I-1J-4618D01*
G01X499330Y342330D01*
X506955Y334705D01*
X509581Y332080D01*
G03X512913Y330700I3333J3334D01*
G01X535337D01*
G03X538845Y332153I-1J4963D01*
G01X544555Y337863D01*
Y337864D01*
X545096Y338405D01*
G03X552000Y355073I-16670J16669D01*
G01Y473500D01*
G02X553414Y476914I4828J0D01*
G01X573500Y497000D01*
G03X576500Y504243I-7245J7244D01*
G01Y570672D01*
G03X574500Y575500I-6828J0D01*
G01X488828Y661172D01*
G03X482000Y664000I-6828J-6829D01*
G01X196177D01*
G03X189900Y661400I0J-8877D01*
G01X178192Y649692D01*
G02X172900Y647500I-5292J5292D01*
G01X97635D01*
G03X93651Y645850I1J-5636D01*
G01X93650D01*
X53699Y605899D01*
Y605900D01*
X53668Y605869D01*
G03X50700Y598699I7170J-7167D01*
G01Y492401D01*
G03X53484Y485676I9509J-2D01*
G01X60370Y478790D01*
G02X60684Y477846I-763J-778D01*
G03X60999Y476902I1078J-165D01*
G01X61848Y476054D01*
G03X62792Y475739I779J762D01*
G02X63736Y475424I165J-1077D01*
G01X64584Y474576D01*
G02X64899Y473632I-763J-779D01*
G03X65213Y472688I1077J-166D01*
G01X66062Y471839D01*
G03X67006Y471525I778J763D01*
G02X67950Y471210I165J-1078D01*
G01X68798Y470362D01*
G02X69113Y469418I-762J-779D01*
G03X69428Y468474I1077J-165D01*
G01X70276Y467625D01*
G03X71220Y467310I779J763D01*
G02X72164Y466996I166J-1077D01*
G01X86713Y452447D01*
G02X87028Y451503I-762J-779D01*
G03X87343Y450559I1077J-165D01*
G01X88191Y449710D01*
G03X89135Y449396I778J763D01*
G02X90079Y449081I165J-1077D01*
G01X90928Y448233D01*
G02X91243Y447289I-763J-779D01*
G03X91557Y446345I1077J-166D01*
G01X92406Y445496D01*
G03X93350Y445182I778J763D01*
G02X94294Y444867I165J-1078D01*
G01X95142Y444018D01*
G02X95457Y443074I-762J-779D01*
G03X95772Y442130I1077J-165D01*
G01X96620Y441282D01*
G03X97564Y440967I779J763D01*
G02X98508Y440653I166J-1077D01*
G01X106688Y432473D01*
G02X107002Y431529I-763J-778D01*
G03X107317Y430585I1078J-165D01*
G01X108166Y429737D01*
G03X109110Y429422I779J762D01*
G02X110054Y429107I165J-1077D01*
G01X110902Y428259D01*
G02X111217Y427315I-763J-779D01*
G03X111531Y426371I1077J-166D01*
G01X112380Y425522D01*
G03X113324Y425208I778J763D01*
G02X114268Y424893I165J-1078D01*
G01X115116Y424045D01*
G02X115431Y423101I-762J-779D01*
G03X115746Y422157I1077J-165D01*
G01X116594Y421308D01*
G03X117538Y420993I779J763D01*
G02X118482Y420679I166J-1077D01*
G01X130831Y408330D01*
G02X132700Y403818I-4513J-4512D01*
G01Y392073D01*
G03X139142Y376518I21998J-1D01*
G01X139580Y376080D01*
G02X140700Y373378I-2700J-2702D01*
G01Y356554D01*
G02X140385Y355793I-1077J0D01*
G01X139301Y354709D01*
G01X143147D02*
X143019D01*
G02X142800Y354800I0J309D01*
G01X142446Y355155D01*
G02X142000Y356230I1075J1076D01*
G01Y373379D01*
G03X140500Y377000I-5121J0D01*
G01X140062Y377438D01*
G02X134000Y392073I14635J14635D01*
G01Y403818D01*
G03X131750Y409250I-7682J0D01*
G01X54404Y486596D01*
G02X52000Y492400I5804J5804D01*
G01Y528492D01*
G02X52445Y529382I1090J11D01*
G03X52890Y530272I-645J879D01*
G01Y531472D01*
G03X52445Y532362I-1090J11D01*
G02X52000Y533252I645J879D01*
G01Y534452D01*
G02X52445Y535342I1090J11D01*
G03X52890Y536232I-645J879D01*
G01Y537432D01*
G03X52445Y538322I-1090J11D01*
G02X52000Y539212I645J879D01*
G01Y540412D01*
G02X52445Y541302I1090J11D01*
G03X52890Y542192I-645J879D01*
G01Y543392D01*
G03X52445Y544282I-1090J11D01*
G02X52000Y545172I645J879D01*
G01Y555191D01*
G02X52445Y556081I1090J11D01*
G03X52890Y556971I-645J879D01*
G01Y558171D01*
G03X52445Y559061I-1090J11D01*
G02X52000Y559951I645J879D01*
G01Y561151D01*
G02X52445Y562041I1090J11D01*
G03X52890Y562931I-645J879D01*
G01Y564131D01*
G03X52445Y565021I-1090J11D01*
G02X52000Y565911I645J879D01*
G01Y576356D01*
G02X52445Y577246I1090J11D01*
G03X52890Y578136I-645J879D01*
G01Y579336D01*
G03X52445Y580226I-1090J11D01*
G02X52000Y581116I645J879D01*
G01Y582316D01*
G02X52445Y583206I1090J11D01*
G03X52890Y584096I-645J879D01*
G01Y585296D01*
G03X52445Y586186I-1090J11D01*
G02X52000Y587076I645J879D01*
G01Y598700D01*
G02X54588Y604949I8838J0D01*
G01X65716Y616077D01*
X65717D01*
G02X66661Y616392I779J-763D01*
G03X67605Y616706I166J1077D01*
G01X68454Y617555D01*
G03X68768Y618499I-763J778D01*
G02X69083Y619443I1078J165D01*
G01X69931Y620291D01*
G02X70875Y620606I779J-762D01*
G03X71819Y620921I165J1077D01*
G01X72668Y621769D01*
G03X72983Y622713I-763J779D01*
G02X73297Y623657I1077J166D01*
G01X81127Y631487D01*
G02X82071Y631802I779J-762D01*
G03X83015Y632117I165J1077D01*
G01X83864Y632965D01*
G03X84178Y633909I-763J778D01*
G02X84493Y634853I1078J165D01*
G01X85342Y635702D01*
G02X86286Y636016I778J-763D01*
G03X87230Y636331I165J1078D01*
G01X88078Y637179D01*
G03X88393Y638123I-763J779D01*
G02X88707Y639067I1077J166D01*
G01X89556Y639916D01*
G02X90500Y640231I779J-763D01*
G03X91444Y640545I166J1077D01*
G01X92292Y641394D01*
G03X92607Y642338I-762J779D01*
G02X92922Y643282I1077J165D01*
G01X94570Y644930D01*
G02X97636Y646200I3066J-3066D01*
G01X172899D01*
G03X179112Y648772I2J8785D01*
G01X190820Y660480D01*
G02X196177Y662700I5358J-5356D01*
G01X481999D01*
G02X487908Y660252I0J-8356D01*
G01X573580Y574580D01*
Y574581D01*
G02X575200Y570671I-3908J-3910D01*
G01Y504244D01*
G02X572580Y497919I-8945J0D01*
G01X552496Y477835D01*
G03X550700Y473499I4336J-4336D01*
G01Y355074D01*
G02X544176Y339324I-22274J0D01*
G01X543255Y338403D01*
Y338402D01*
X537926Y333073D01*
G02X535336Y332000I-2590J2590D01*
G01X512914D01*
G02X510500Y333000I0J3414D01*
G01X507800Y335700D01*
X507799D01*
X500243Y343256D01*
X500181Y343317D01*
G03X496001Y345047I-4181J-4188D01*
G01X490528D01*
G03X487999Y344000I0J-3578D01*
G01X487852Y343853D01*
G02X487000Y343500I-852J852D01*
G03X483985Y342251I0J-4264D01*
G01X483662Y341928D01*
G01Y345865D02*
X484648Y346851D01*
G02X486130Y347465I1482J-1482D01*
G01X498187D01*
G02X501920Y345919I1J-5278D01*
G01X510669Y337170D01*
G03X513976Y335800I3307J3307D01*
G01X530813D01*
G03X534205Y337205I0J4797D01*
G01X538999Y341999D01*
Y342000D01*
X539968Y342969D01*
G03X543917Y352501I-9530J9532D01*
G01Y476404D01*
G02X545580Y480419I5680J-1D01*
G01X565580Y500419D01*
G03X568200Y506744I-6325J6325D01*
G01Y566795D01*
G03X565591Y573093I-8905J0D01*
G01X565590Y573092D01*
X486591Y652092D01*
X485211Y653472D01*
G03X481001Y655217I-4212J-4211D01*
G01X199324D01*
G03X195406Y653594I0J-5541D01*
G01X194792Y652980D01*
G03X194477Y652036I763J-779D01*
G02X194163Y651092I-1077J-166D01*
G01X193314Y650244D01*
G02X192370Y649929I-779J762D01*
G03X191426Y649614I-165J-1077D01*
G01X190578Y648766D01*
G03X190263Y647822I762J-779D01*
G02X189948Y646878I-1077J-165D01*
G01X189100Y646029D01*
G02X188156Y645715I-778J763D01*
G03X187212Y645400I-165J-1078D01*
G01X181642Y639830D01*
G02X178955Y638717I-2687J2687D01*
G01X107852D01*
G03X102500Y636500I0J-7569D01*
G01X65900Y599900D01*
G03X63500Y594106I5794J-5794D01*
G01Y496100D01*
G03X65692Y490808I7484J0D01*
G01X142750Y413750D01*
G02X146000Y405904I-7846J-7846D01*
G01Y388364D01*
G03X150500Y377500I15364J0D01*
G02X153500Y370257I-7243J-7243D01*
G01Y356500D01*
G03X153602Y356254I348J0D01*
G01X155147Y354709D01*
G01X151301D02*
X151885Y355293D01*
G03X152200Y356054I-762J761D01*
G01Y370258D01*
X152199Y370257D01*
G03X149580Y376580I-8942J0D01*
G02X144700Y388364I11785J11783D01*
G01Y405903D01*
G03X141830Y412831I-9796J0D01*
G01X65430Y489230D01*
X64772Y489888D01*
G02X62200Y496101I6213J6211D01*
G01Y594107D01*
G02X64980Y600819I9494J-1D01*
G01Y600820D01*
X101580Y637420D01*
X101581D01*
G02X107851Y640017I6271J-6272D01*
G01X178954D01*
G03X180722Y640749I0J2500D01*
G01X194487Y654514D01*
G02X199323Y656517I4837J-4838D01*
G01X481000D01*
G02X486131Y654392I0J-7257D01*
G01X566511Y574012D01*
G02X569500Y566796I-7216J-7216D01*
G01Y506743D01*
G02X566500Y499500I-10245J1D01*
G01X546500Y479500D01*
G03X545217Y476403I3097J-3097D01*
G01Y352500D01*
G02X540888Y342049I-14780J0D01*
G01X535124Y336285D01*
G02X530812Y334500I-4311J4312D01*
G01X513975D01*
G02X509750Y336250I1J5977D01*
G01X501000Y345000D01*
G03X498187Y346165I-2813J-2813D01*
G01X488323D01*
G03X487599Y345865I0J-1024D01*
G01X162801Y354709D02*
X163385Y355293D01*
G03X163700Y356054I-762J761D01*
G01Y368878D01*
G03X162580Y371580I-3820J0D01*
G02X158527Y377186I15405J15405D01*
G02X156199Y386985I19458J9799D01*
G01Y392073D01*
X156200Y392074D01*
Y406828D01*
G03X153631Y413030I-8772J0D01*
G01X76979Y489681D01*
G02X73700Y497601I7920J7918D01*
G01Y596034D01*
G02X76531Y602870I9665J2D01*
G01X76530D01*
X104513Y630853D01*
G02X110421Y633300I5908J-5908D01*
G01X184100D01*
G03X188709Y635209I0J6518D01*
G01X201100Y647600D01*
G02X206411Y649800I5311J-5311D01*
G01X476200D01*
G02X483883Y646617I-1J-10866D01*
G01X485600Y644901D01*
X561387Y569114D01*
G02X561395Y569105I-2831J-2525D01*
G02X562500Y566427I-2695J-2679D01*
G01Y510412D01*
G02X559380Y502878I-10654J-1D01*
G01X558850Y502349D01*
X539499Y482998D01*
G03X538301Y480104I2895J-2893D01*
G01X538300Y480105D01*
Y378921D01*
G03X539800Y375300I5121J0D01*
G02X541300Y371679I-3621J-3621D01*
G01Y350475D01*
G02X539169Y345330I-7276J0D01*
G01X533208Y339369D01*
G02X529900Y338000I-3306J3308D01*
G01X519829D01*
G02X515000Y340000I1J6831D01*
G01X510111Y344888D01*
G03X508393Y345600I-1718J-1717D01*
G01X507435D01*
G02X505076Y346577I-1J3335D01*
G01X503351Y348301D01*
X501687Y349965D01*
G03X497257Y351800I-4430J-4430D01*
G01X494900D01*
G03X493705Y351305I0J-1690D01*
G01X493600Y351200D01*
G02X492151Y350600I-1449J1449D01*
G01X489526D01*
G03X487599Y349802I0J-2725D01*
G01X483662D02*
G02X488727Y351900I5065J-5065D01*
G01X492152D01*
G03X492680Y352120I-2J748D01*
G01X492785Y352225D01*
G02X494900Y353100I2114J-2115D01*
G01X497258D01*
G02X502607Y350885I0J-7566D01*
G01X505996Y347496D01*
G03X507435Y346900I1439J1439D01*
G01X508394D01*
G02X511031Y345808I0J-3730D01*
G01X515919Y340920D01*
G03X519830Y339300I3911J3911D01*
G01X529901D01*
G03X532289Y340289I0J3377D01*
G01X538250Y346250D01*
G03X539999Y350475I-4227J4224D01*
G01X540000Y350474D01*
Y371678D01*
G03X538880Y374380I-3820J0D01*
G02X537000Y378920I4542J4540D01*
G01Y480104D01*
G02X538579Y483918I5393J1D01*
G01X558496Y503834D01*
G03X561199Y510412I-6651J6577D01*
G01X561200Y510411D01*
Y566416D01*
G03X560468Y568184I-2500J0D01*
G01X559314Y569338D01*
X559318Y569342D01*
X559330Y569331D01*
X484064Y644598D01*
X482963Y645697D01*
G03X476200Y648500I-6765J-6762D01*
G01X206412D01*
G03X202020Y646680I0J-6210D01*
G01X200528Y645188D01*
G03X200213Y644244I762J-779D01*
G02X199898Y643300I-1077J-165D01*
G01X199050Y642451D01*
G02X198106Y642136I-779J763D01*
G03X197162Y641822I-166J-1077D01*
G01X196313Y640973D01*
G03X195998Y640029I763J-779D01*
G02X195684Y639085I-1077J-166D01*
G01X194835Y638237D01*
G02X193891Y637922I-779J762D01*
G03X193498Y637910I-164J-1077D01*
G03X192947Y637607I227J-1066D01*
G01X189629Y634289D01*
G02X184099Y632000I-5528J5530D01*
G01X110421D01*
G03X105433Y629933I1J-7054D01*
G01X77450Y601950D01*
G03X75000Y596035I5915J-5915D01*
G01Y497600D01*
G03X77899Y490601I9898J0D01*
G01X154550Y413950D01*
G02X157500Y406828I-7122J-7122D01*
G01Y386985D01*
G03X159689Y377771I20485J0D01*
G03X163500Y372500I18296J9215D01*
G02X165000Y368879I-3621J-3621D01*
G01Y356500D01*
G03X165102Y356254I348J0D01*
G01X166647Y354709D01*
G01X167993Y328699D02*
X167992D01*
G02X167326Y328975I1J944D01*
G01X167210Y329091D01*
G02X166500Y330802I1707J1711D01*
G01Y334439D01*
G02X167250Y336250I2561J0D01*
G01X174793Y343793D01*
G03X175500Y345500I-1707J1707D01*
G01Y365429D01*
G03X170500Y377500I-17071J0D01*
G01X168186Y379815D01*
G02X166847Y383046I3231J3232D01*
G01X166846Y389086D01*
Y390770D01*
G02X167291Y391660I1090J11D01*
G03X167736Y392550I-645J879D01*
G01Y393750D01*
G03X167291Y394640I-1090J11D01*
G02X166846Y395530I645J879D01*
G01Y396730D01*
G02X167291Y397620I1090J11D01*
G03X167736Y398510I-645J879D01*
G01Y399710D01*
G03X167291Y400600I-1090J11D01*
G02X166846Y401490I645J879D01*
G01Y409346D01*
G03X163800Y416700I-10400J0D01*
G01X90770Y489730D01*
G02X87800Y496900I7170J7170D01*
G01Y599617D01*
G02X90050Y605049I7682J0D01*
G01X108001Y623000D01*
G02X112104Y624700I4104J-4104D01*
G01X189799D01*
G03X192768Y625928I2J4198D01*
G01X197840Y631000D01*
G02X198784Y631315I779J-762D01*
G03X199728Y631630I165J1077D01*
G01X200577Y632478D01*
G03X200892Y633422I-763J779D01*
G02X201206Y634366I1077J166D01*
G01X205520Y638680D01*
G02X213050Y641800I7531J-7529D01*
G01X475638D01*
G02X478580Y640581I-1J-4163D01*
G01Y640580D01*
X511580Y607580D01*
X512500Y606661D01*
X552330Y566831D01*
G02X554200Y562316I-4515J-4515D01*
G01Y512737D01*
G02X551939Y507278I-7720J0D01*
G01X532330Y487669D01*
Y487670D01*
X531828Y487168D01*
G03X530200Y483234I3934J-3932D01*
G01Y378625D01*
G03X531730Y374931I5226J1D01*
G01Y374930D01*
X534830Y371830D01*
G02X536000Y369007I-2822J-2823D01*
G01Y350216D01*
X535999Y350217D01*
G02X535380Y348719I-2117J-2D01*
G01X533052Y346391D01*
G02X530900Y345500I-2152J2153D01*
G01X528300D01*
G02X526989Y346043I0J1854D01*
G01X526500Y346532D01*
G01X164147Y328699D02*
X164759Y329311D01*
G03X165200Y330376I-1065J1065D01*
G01Y334439D01*
G02X166330Y337170I3862J2D01*
G01X173873Y344713D01*
G03X174200Y345500I-787J788D01*
G01X174199Y364121D01*
Y365427D01*
X174200Y365428D01*
G03X169580Y376580I-15770J0D01*
G01X167266Y378895D01*
G02X165546Y383046I4150J4152D01*
G01Y409347D01*
X165545Y409346D01*
G03X162881Y415780I-9100J1D01*
G01X89850Y488810D01*
G02X86500Y496899I8091J8089D01*
G01Y599616D01*
G02X89131Y605969I8982J1D01*
G01X89130D01*
X107081Y623920D01*
G02X112103Y626000I5023J-5024D01*
G01X189800D01*
G03X191848Y626848I0J2897D01*
G01X204600Y639600D01*
G02X213050Y643100I8450J-8450D01*
G01X475639D01*
G02X479500Y641500I-2J-5463D01*
G01X553249Y567751D01*
G02X555500Y562316I-5434J-5434D01*
G01Y512737D01*
G02X552858Y506358I-9020J-1D01*
G01X532748Y486248D01*
G03X531500Y483235I3013J-3013D01*
G01Y378626D01*
G03X532650Y375850I3926J0D01*
G01X535750Y372750D01*
G02X537300Y369008I-3742J-3742D01*
G01Y350217D01*
G02X536299Y347799I-3417J-2D01*
G01X533988Y345488D01*
X533989D01*
X533972Y345471D01*
G02X530899Y344200I-3071J3074D01*
G01X528300D01*
G03X527328Y343798I-1J-1374D01*
G01X526500Y342969D01*
G01X179622Y328749D02*
X178466Y329905D01*
G02X178349Y330188I284J283D01*
G01Y331127D01*
X178300Y331176D01*
Y333965D01*
X178301Y333964D01*
G02X180420Y339080I7235J0D01*
G03X184000Y347724I-8646J8644D01*
G01Y367293D01*
G03X179370Y378471I-15808J0D01*
G02X174800Y389501I11028J11031D01*
G01Y411501D01*
G03X171477Y419522I-11344J-1D01*
G01X99316Y491684D01*
G02X96700Y498000I6317J6316D01*
G01Y538189D01*
G02X97145Y539079I1090J11D01*
G03X97590Y539969I-645J879D01*
G01Y541169D01*
G03X97145Y542059I-1090J11D01*
G02X96700Y542949I645J879D01*
G01Y544149D01*
G02X97145Y545039I1090J11D01*
G03X97590Y545929I-645J879D01*
G01Y547129D01*
G03X97145Y548019I-1090J11D01*
G02X96700Y548909I645J879D01*
G01Y550109D01*
G02X97145Y550999I1090J11D01*
G03X97590Y551889I-645J879D01*
G01Y553089D01*
G03X97145Y553979I-1090J11D01*
G02X96700Y554869I645J879D01*
G01Y598664D01*
G02X99200Y604700I8536J0D01*
G01X110250Y615750D01*
X110619Y616120D01*
G02X115000Y617934I4380J-4381D01*
G01X199299D01*
G03X201473Y618833I2J3073D01*
G01X216842Y634202D01*
G02X218610Y634934I1768J-1768D01*
G01X471106D01*
G02X475581Y633080I0J-6327D01*
G01X475580D01*
X502580Y606080D01*
X505800Y602861D01*
X545080Y563581D01*
G02X546700Y559670I-3911J-3911D01*
G01Y514537D01*
G02X544580Y509419I-7238J0D01*
G01X534830Y499670D01*
X525080Y489920D01*
G03X523434Y485945I3977J-3975D01*
G01Y380699D01*
G03X525177Y376484I5969J1D01*
G01X531230Y370431D01*
G02X532200Y368089I-2342J-2342D01*
G01Y353704D01*
G02X531730Y352569I-1605J0D01*
G01X530130Y350969D01*
G02X528756Y350400I-1374J1374D01*
G01X522400D01*
G02X521035Y350966I1J1931D01*
G01X520500Y351500D01*
G01X175776Y328749D02*
X176932Y329905D01*
G03X177049Y330188I-284J283D01*
G01Y330588D01*
X177000Y330637D01*
Y333964D01*
G02X179500Y340000I8536J0D01*
G03X182700Y347725I-7725J7725D01*
G01Y364800D01*
X182699Y367293D01*
G03X178450Y377551I-14507J0D01*
G02X173500Y389500I11949J11950D01*
G01Y411500D01*
G03X170557Y418602I-10043J-1D01*
G01X98396Y490764D01*
G02X95400Y497999I7237J7235D01*
G01Y598663D01*
G02X98281Y605620I9836J2D01*
G01X98280D01*
X109328Y616668D01*
X109329D01*
X109699Y617039D01*
G02X115000Y619235I5301J-5300D01*
G01Y619234D01*
X199300D01*
G03X200553Y619753I0J1772D01*
G01X215921Y635121D01*
G02X218608Y636234I2687J-2687D01*
G01X471106D01*
G02X476501Y634000I2J-7627D01*
G01X476764Y633736D01*
X546000Y564500D01*
G02X548000Y559671I-4831J-4830D01*
G01Y514536D01*
G02X545500Y508500I-8538J1D01*
G01X526000Y489000D01*
G03X524734Y485944I3056J-3056D01*
G01Y380700D01*
G03X526102Y377399I4669J1D01*
G01X526150Y377350D01*
X532149Y371351D01*
G02X533500Y368089I-3261J-3261D01*
G01Y353704D01*
G02X532649Y351649I-2905J-1D01*
G01X531050Y350050D01*
G02X528756Y349100I-2293J2293D01*
G01X522400D01*
G03X521142Y348579I0J-1779D01*
G01X520500Y347937D01*
G01X198864Y323297D02*
X199587Y324020D01*
G03X200200Y325500I-1480J1480D01*
G01Y359000D01*
G03X195391Y370609I-16417J0D01*
G01X185000Y381000D01*
G02X180500Y391864I10864J10864D01*
G01Y412581D01*
G03X176201Y422960I-14678J0D01*
G01X106284Y492876D01*
G02X103500Y499601I6724J6722D01*
G01Y597101D01*
G02X106496Y604336I10234J0D01*
G01X112830Y610670D01*
G02X117252Y612500I4419J-4422D01*
G01X204782D01*
G03X211300Y615200I0J9218D01*
G01X222913Y626813D01*
G02X229400Y629500I6487J-6487D01*
G01X468319D01*
G02X473750Y627251I0J-7682D01*
G01X538500Y562501D01*
Y562500D01*
G02X541000Y556464I-6038J-6037D01*
G01Y518500D01*
X541001D01*
G02X537465Y509963I-12071J-1D01*
G01X537248Y509748D01*
X521224Y493724D01*
X520121Y492622D01*
G03X518000Y487500I5122J-5121D01*
G01Y383100D01*
G03X519838Y378662I6277J0D01*
G01X528400Y370100D01*
G02X530000Y366237I-3865J-3864D01*
G01Y356778D01*
G02X529449Y355449I-1880J1D01*
G01X529149Y355149D01*
X529150D01*
X529136Y355135D01*
G02X528000Y354500I-1690J1690D01*
G03X526500Y352969I466J-1957D01*
G01X208338Y323297D02*
X208752Y323711D01*
G03X209700Y326000I-2289J2289D01*
G01Y365928D01*
G03X208968Y367696I-2500J0D01*
G01X194329Y382335D01*
G02X187700Y398691I16863J16356D01*
G01Y411499D01*
G03X180303Y429356I-25253J0D01*
G01X179078Y430581D01*
X114330Y495330D01*
X114331D01*
G02X111000Y503373I8041J8041D01*
G01Y593345D01*
G02X115000Y603000I13657J-2D01*
G02X121036Y605500I6036J-6036D01*
G01X213700D01*
G03X217285Y606985I0J5070D01*
G01X231687Y621387D01*
G02X234374Y622500I2687J-2687D01*
G01X464269D01*
G02X471150Y619651I1J-9731D01*
G01X531650Y559151D01*
Y559150D01*
G02X534000Y553476I-5676J-5675D01*
G01Y521036D01*
G02X531500Y515000I-8538J1D01*
G01X513750Y497250D01*
G03X511000Y490611I6639J-6639D01*
G01Y384100D01*
G03X512485Y380515I5070J0D01*
G01X525600Y367400D01*
G02X526500Y365227I-2175J-2174D01*
G01Y363134D01*
G02X525699Y361199I-2734J-1D01*
G01X525400Y360900D01*
G02X523466Y360099I-1934J1933D01*
G01X522300D01*
G03X521211Y359648I0J-1540D01*
G01X520500Y358937D01*
G01X202710Y323297D02*
X202202Y323805D01*
G02X201500Y325500I1695J1695D01*
G01Y328262D01*
G02X201945Y329152I1090J11D01*
G03X202390Y330042I-645J879D01*
G01Y331242D01*
G03X201945Y332132I-1090J11D01*
G02X201500Y333022I645J879D01*
G01Y334222D01*
G02X201945Y335112I1090J11D01*
G03X202390Y336002I-645J879D01*
G01Y337202D01*
G03X201945Y338092I-1090J11D01*
G02X201500Y338982I645J879D01*
G01Y340182D01*
G02X201945Y341072I1090J11D01*
G03X202390Y341962I-645J879D01*
G01Y343162D01*
G03X201945Y344052I-1090J11D01*
G02X201500Y344942I645J879D01*
G01Y348691D01*
G02X201945Y349581I1090J11D01*
G03X202390Y350471I-645J879D01*
G01Y351671D01*
G03X201945Y352561I-1090J11D01*
G02X201500Y353451I645J879D01*
G01Y359001D01*
G03X196311Y371529I-17718J0D01*
G01X185920Y381920D01*
G02X181800Y391864I9943J9945D01*
G01X181801Y409500D01*
X181800D01*
Y412580D01*
G03X177121Y423880I-15979J2D01*
G01X107204Y493796D01*
G02X104800Y499600I5804J5804D01*
G01Y597100D01*
G02X107416Y603416I8933J0D01*
G01X113750Y609750D01*
G02X117251Y611200I3501J-3501D01*
G01X204783D01*
G03X212220Y614280I0J10519D01*
G01X223833Y625893D01*
G02X229399Y628200I5568J-5566D01*
G01X468319D01*
G02X472830Y626331I-1J-6381D01*
G01X537580Y561581D01*
G02X539700Y556463I-5118J-5118D01*
G01Y518500D01*
G02X536546Y510884I-10770J-1D01*
G01X536330Y510669D01*
X520305Y494644D01*
X519752Y494093D01*
X519201Y493542D01*
G03X516700Y487499I6043J-6040D01*
G01Y383099D01*
G03X518918Y377742I7578J0D01*
G01X519530Y377130D01*
X527480Y369181D01*
G02X528700Y366236I-2945J-2945D01*
G01Y356779D01*
G02X528530Y356369I-580J0D01*
G01X528216Y356055D01*
G02X527600Y355800I-616J617D01*
G02X526972Y356060I0J888D01*
G01X526500Y356532D01*
G01X212134Y323297D02*
X212129D01*
G02X211787Y323435I0J493D01*
G01X211685Y323533D01*
G02X211000Y325145I1553J1611D01*
G01Y331725D01*
G02X211445Y332615I1090J11D01*
G03X211890Y333505I-645J879D01*
G01Y334705D01*
G03X211445Y335595I-1090J11D01*
G02X211000Y336485I645J879D01*
G01Y337685D01*
G02X211445Y338575I1090J11D01*
G03X211890Y339465I-645J879D01*
G01Y340665D01*
G03X211445Y341555I-1090J11D01*
G02X211000Y342445I645J879D01*
G01Y365930D01*
G03X209887Y368617I-3800J0D01*
G01X195256Y383248D01*
G02X189000Y398692I15936J15444D01*
G01Y411500D01*
G03X181223Y430276I-26554J0D01*
G01X179998Y431501D01*
X115250Y496250D01*
G02X112300Y503372I7122J7122D01*
G01Y593344D01*
G02X115920Y602080I12356J-2D01*
G02X121036Y604200I5117J-5115D01*
G01X213701D01*
G03X218205Y606065I0J6371D01*
G01X232608Y620468D01*
G02X234376Y621200I1768J-1768D01*
G01X464269D01*
G02X470230Y618731I0J-8430D01*
G01X530730Y558231D01*
G02X532700Y553475I-4756J-4756D01*
G01Y521037D01*
G02X530580Y515919I-7238J0D01*
G01X521705Y507045D01*
X512830Y498170D01*
G03X509700Y490612I7560J-7558D01*
G01Y384099D01*
G03X511565Y379595I6371J0D01*
G01X524680Y366481D01*
G02X525200Y365226I-1255J-1255D01*
G01Y363133D01*
G02X524780Y362119I-1434J0D01*
G01X524480Y361819D01*
G02X523466Y361399I-1014J1014D01*
G01X522300D01*
G02X521106Y361893I-1J1688D01*
G01X520500Y362500D01*
G01X519706Y314000D02*
X519061Y313356D01*
G03X518500Y312000I1356J-1355D01*
G02X516378Y306878I-7243J0D01*
G01X505500Y296000D01*
G02X498257Y293000I-7243J7243D01*
G01X483211D01*
G03X476602Y290261I1J-9346D01*
G01X474366Y288028D01*
G02X471161Y286700I-3206J3207D01*
G01X435897D01*
G03X433000Y285500I0J-4097D01*
G01X418002Y270502D01*
X417830Y270329D01*
G02X411000Y267499I-6830J6827D01*
G01Y267500D01*
X383676D01*
G03X378884Y265515I0J-6777D01*
G01X345448Y232079D01*
G03X345134Y231135I763J-778D01*
G02X344819Y230191I-1078J-165D01*
G01X343970Y229343D01*
G02X343026Y229028I-779J762D01*
G03X342082Y228713I-165J-1077D01*
G01X341234Y227865D01*
G03X340919Y226921I763J-779D01*
G02X340605Y225977I-1077J-166D01*
G01X339756Y225128D01*
G02X338812Y224814I-778J763D01*
G03X337868Y224499I-165J-1078D01*
G01X337020Y223651D01*
G03X336705Y222707I762J-779D01*
G02X336390Y221763I-1077J-165D01*
G01X335542Y220914D01*
G02X334598Y220599I-779J763D01*
G03X333654Y220285I-166J-1077D01*
G01X330784Y217415D01*
X330524Y217154D01*
G03X328140Y211400I5754J-5755D01*
G01Y209222D01*
G03X328585Y208332I1090J-11D01*
G02X329030Y207442I-645J-879D01*
G01Y206242D01*
G02X328585Y205352I-1090J-11D01*
G03X328140Y204462I645J-879D01*
G01Y203262D01*
G03X328585Y202372I1090J-11D01*
G02X329030Y201482I-645J-879D01*
G01Y200282D01*
G02X328585Y199392I-1090J-11D01*
G03X328140Y198502I645J-879D01*
G01Y197302D01*
G03X328585Y196412I1090J-11D01*
G02X329030Y195522I-645J-879D01*
G01Y194322D01*
G02X328585Y193432I-1090J-11D01*
G03X328140Y192542I645J-879D01*
G01Y180006D01*
G03X328585Y179116I1090J-11D01*
G02X329030Y178226I-645J-879D01*
G01Y177026D01*
G02X328585Y176136I-1090J-11D01*
G03X328140Y175246I645J-879D01*
G01Y160990D01*
G03X328346Y160495I701J1D01*
G01X335682Y153159D01*
G03X336626Y152845I778J763D01*
G02X337570Y152530I165J-1078D01*
G01X338418Y151681D01*
G02X338733Y150737I-762J-779D01*
G03X339048Y149793I1077J-165D01*
G01X339896Y148945D01*
G03X340840Y148630I779J763D01*
G02X341784Y148316I166J-1077D01*
G01X342633Y147467D01*
G02X342947Y146523I-763J-778D01*
G03X343262Y145579I1078J-165D01*
G01X344110Y144731D01*
G03X345054Y144416I779J762D01*
G02X345998Y144101I165J-1077D01*
G01X346847Y143253D01*
G02X347162Y142309I-763J-779D01*
G03X347476Y141365I1077J-166D01*
G01X351089Y137752D01*
G03X351584Y137546I496J495D01*
G01X365600D01*
G02X367983Y136559I0J-3370D01*
G01X368296Y136246D01*
G01X371456Y136221D02*
X370787Y135552D01*
G02X368600Y134646I-2187J2187D01*
G01X366800D02*
G02X366038Y134961I-1J1077D01*
G01X366000Y135000D01*
X365287Y135713D01*
G03X364830Y136045I-1285J-1289D01*
G03X364000Y136246I-831J-1619D01*
G01X351584D01*
G02X350169Y136832I0J2001D01*
G01X327426Y159575D01*
G02X326840Y160990I1415J1415D01*
G01Y211401D01*
G02X329603Y218073I9438J0D01*
G01X377965Y266435D01*
G02X383675Y268800I5711J-5712D01*
G01X411000D01*
G03X416909Y271247I1J8356D01*
G01X417080Y271419D01*
X432081Y286420D01*
G02X435896Y288000I3816J-3817D01*
G01X471160D01*
G03X473447Y288948I-1J3235D01*
G01X475682Y291181D01*
G02X483210Y294300I7529J-7528D01*
G01X498257D01*
G03X504580Y296920I-1J8942D01*
G01X515458Y307798D01*
G03X517200Y312001I-4200J4203D01*
G03X516734Y313126I-1591J0D01*
G01X515860Y314000D01*
G01X368314Y142505D02*
Y142385D01*
X367004Y141076D01*
G02X366629Y140920I-376J375D01*
G01X359107D01*
G02X358612Y141126I1J701D01*
G01X355208Y144530D01*
G02X354894Y145474I763J778D01*
G03X354579Y146418I-1078J165D01*
G01X353730Y147266D01*
G03X352786Y147581I-779J-762D01*
G02X351842Y147896I-165J1077D01*
G01X346779Y152959D01*
G02X346465Y153903I763J778D01*
G03X346150Y154847I-1078J165D01*
G01X345302Y155695D01*
G03X344358Y156010I-779J-763D01*
G02X343414Y156324I-166J1077D01*
G01X337183Y162555D01*
G02X336229Y164858I2303J2303D01*
G01Y175094D01*
G02X336674Y175984I1090J11D01*
G03X337119Y176874I-645J879D01*
G01Y178074D01*
G03X336674Y178964I-1090J11D01*
G02X336229Y179854I645J879D01*
G01Y181054D01*
G02X336674Y181944I1090J11D01*
G03X337119Y182834I-645J879D01*
G01Y184034D01*
G03X336674Y184924I-1090J11D01*
G02X336229Y185814I645J879D01*
G01Y187014D01*
G02X336674Y187904I1090J11D01*
G03X337119Y188794I-645J879D01*
G01Y189994D01*
G03X336674Y190884I-1090J11D01*
G02X336229Y191774I645J879D01*
G01Y210600D01*
G02X337802Y214396I5369J-1D01*
G01X345002Y221597D01*
X365021Y241616D01*
G02X365965Y241931I779J-762D01*
G03X366909Y242246I165J1077D01*
G01X367758Y243094D01*
G03X368073Y244038I-763J779D01*
G02X368387Y244982I1077J166D01*
G01X369236Y245831D01*
G02X370180Y246145I778J-763D01*
G03X371124Y246460I165J1078D01*
G01X371972Y247309D01*
G03X372287Y248253I-762J779D01*
G02X372602Y249197I1077J165D01*
G01X377252Y253847D01*
X377421Y254017D01*
G02X383900Y256700I6478J-6479D01*
G01X410501D01*
G03X416267Y259087I-1J8161D01*
G01X416334Y259153D01*
X434840Y277659D01*
G02X440492Y280000I5652J-5652D01*
G01X473658D01*
G03X477789Y281710I2J5841D01*
G01X479682Y283603D01*
G02X480157Y283800I475J-474D01*
G01X498629D01*
G03X505749Y286749I-1J10071D01*
G01X523227Y304227D01*
G03X525825Y310500I-6274J6273D01*
G01Y317600D01*
G02X526237Y318593I1405J-1D01*
G01X527002Y319359D01*
G01X523348D02*
X524113Y318593D01*
G02X524525Y317600I-993J-994D01*
G01Y310499D01*
G02X522307Y305147I-7571J2D01*
G01X521830Y304670D01*
Y304669D01*
X504830Y287669D01*
G02X498628Y285100I-6202J6202D01*
G01X480157D01*
G03X478762Y284522I0J-1972D01*
G01X476870Y282630D01*
G02X473659Y281300I-3211J3211D01*
G01X440493D01*
G03X433920Y278578I-2J-9293D01*
G01X415421Y260079D01*
X415351Y260010D01*
G02X410500Y258000I-4852J4851D01*
G01X383900D01*
Y258001D01*
G03X376500Y254935I0J-10463D01*
G01X376330Y254764D01*
X336882Y215316D01*
G03X334929Y210601I4716J-4715D01*
G01Y164857D01*
G03X336263Y161636I4557J1D01*
G01Y161635D01*
X357692Y140206D01*
G03X359107Y139620I1415J1415D01*
G01X367776D01*
G02X368305Y139401I0J-748D01*
G01X371493Y145667D02*
Y145449D01*
G02X371100Y144500I-1342J0D01*
G02X370146Y144105I-954J954D01*
G01X368800D01*
G01X367100D02*
X366419D01*
G02X365504Y144484I0J1294D01*
G03X364349Y144900I-1156J-1397D01*
G01X360816D01*
G02X358501Y145859I0J3274D01*
G01X357581Y146780D01*
X354009Y150352D01*
G02X352727Y153447I3096J3096D01*
G01Y154735D01*
G03X351852Y156849I-2989J1D01*
G01X351500Y157200D01*
X342600Y166100D01*
X342307Y166394D01*
G02X341720Y167809I1415J1416D01*
G01Y196101D01*
G02X346710Y208150I17042J0D01*
G01X357601Y219041D01*
G03X359100Y222660I-3619J3619D01*
G01Y225200D01*
G02X360019Y227419I3138J0D01*
G01X382800Y250200D01*
G02X385456Y251300I2656J-2656D01*
G01X414002D01*
G03X417614Y252796I0J5108D01*
G01X437409Y272591D01*
G02X441776Y274400I4367J-4367D01*
G01X476006D01*
G03X479608Y275892I0J5094D01*
G01X481529Y277813D01*
G02X482944Y278400I1416J-1415D01*
G01X502930D01*
G03X508000Y280500I0J7170D01*
G01X527500Y300000D01*
X527659Y300160D01*
G03X530700Y307500I-7340J7341D01*
G01Y323443D01*
G03X530699Y323482I-2908J-55D01*
G03X529848Y325500I-2909J-38D01*
G01X533502D02*
G03X532645Y325145I0J-1212D01*
G01X532500Y325000D01*
G03X532000Y323793I1207J-1207D01*
G01Y307499D01*
G02X528580Y299242I-11681J1D01*
G01X528422Y299083D01*
X526949Y297610D01*
G03X526634Y296666I762J-779D01*
G02X526319Y295722I-1077J-165D01*
G01X525471Y294873D01*
G02X524527Y294559I-778J763D01*
G03X523583Y294244I-165J-1078D01*
G01X522734Y293395D01*
G03X522420Y292451I763J-778D01*
G02X522105Y291507I-1078J-165D01*
G01X521257Y290659D01*
G02X520313Y290344I-779J763D01*
G03X519369Y290030I-166J-1077D01*
G01X518520Y289181D01*
G03X518205Y288237I763J-779D01*
G02X517891Y287293I-1077J-166D01*
G01X517042Y286445D01*
G02X516098Y286130I-779J762D01*
G03X515154Y285815I-165J-1077D01*
G01X508920Y279581D01*
G02X502930Y277100I-5989J5989D01*
G01X482945D01*
G03X482449Y276894I1J-702D01*
G01X480527Y274972D01*
G02X476007Y273100I-4521J4522D01*
G01X441777D01*
G03X438329Y271671I0J-4875D01*
G01X437480Y270822D01*
G03X437166Y269878I763J-778D01*
G02X436851Y268934I-1078J-165D01*
G01X436003Y268086D01*
G02X435059Y267771I-779J763D01*
G03X434115Y267457I-166J-1077D01*
G01X426963Y260305D01*
G03X426648Y259361I762J-779D01*
G02X426333Y258417I-1077J-165D01*
G01X425485Y257568D01*
G02X424541Y257254I-778J763D01*
G03X423597Y256939I-165J-1078D01*
G01X422748Y256090D01*
G03X422434Y255146I763J-778D01*
G02X422119Y254202I-1078J-165D01*
G01X421271Y253354D01*
G02X420327Y253039I-779J763D01*
G03X419383Y252725I-166J-1077D01*
G01X418534Y251876D01*
G02X414001Y250000I-4530J4533D01*
G01X410057D01*
G03X409167Y249555I-11J-1090D01*
G02X408277Y249110I-879J645D01*
G01X407077D01*
G02X406187Y249555I-11J1090D01*
G03X405297Y250000I-879J-645D01*
G01X391416D01*
G03X390526Y249555I-11J-1090D01*
G02X389636Y249110I-879J645D01*
G01X388436D01*
G02X387546Y249555I-11J1090D01*
G03X386656Y250000I-879J-645D01*
G01X385456D01*
G03X383720Y249280I1J-2455D01*
G01X378657Y244217D01*
G03X378342Y243273I763J-779D01*
G02X378028Y242329I-1077J-166D01*
G01X377179Y241481D01*
G02X376235Y241166I-779J762D01*
G03X375291Y240851I-165J-1077D01*
G01X374442Y240002D01*
G03X374128Y239058I763J-778D01*
G02X373813Y238114I-1078J-165D01*
G01X372965Y237266D01*
G02X372021Y236951I-779J763D01*
G03X371077Y236637I-166J-1077D01*
G01X370228Y235788D01*
G03X369913Y234844I763J-779D01*
G02X369599Y233900I-1077J-166D01*
G01X368750Y233052D01*
G02X367806Y232737I-779J762D01*
G03X366862Y232422I-165J-1077D01*
G01X365315Y230875D01*
G03X365001Y229931I763J-778D01*
G02X364686Y228987I-1078J-165D01*
G01X363837Y228139D01*
G02X362893Y227824I-779J762D01*
G03X361949Y227509I-165J-1077D01*
G01X360939Y226499D01*
G03X360401Y225200I1299J-1299D01*
G01X360400Y225201D01*
Y222660D01*
G02X358521Y218121I-6419J-1D01*
G01X357672Y217272D01*
G03X357358Y216328I763J-778D01*
G02X357043Y215384I-1078J-165D01*
G01X356195Y214536D01*
G02X355251Y214221I-779J763D01*
G03X354307Y213907I-166J-1077D01*
G01X347630Y207230D01*
G03X343020Y196100I11131J-11130D01*
G01Y167810D01*
G03X343226Y167314I702J1D01*
G01X352771Y157769D01*
G02X354027Y154737I-3032J-3032D01*
G01Y153448D01*
G03X354929Y151272I3078J1D01*
G01X358500Y147700D01*
X359040Y147159D01*
Y147161D01*
X359421Y146779D01*
G03X360817Y146200I1396J1394D01*
G01X364350D01*
G02X366333Y145486I-1J-3113D01*
G01X367846D01*
G03X368314Y145680I0J662D01*
G01X360126Y152747D02*
X359736Y153136D01*
Y153137D01*
G02X359109Y154651I1516J1515D01*
G01Y160802D01*
G03X358904Y161297I-701J0D01*
G01X349007Y171194D01*
G02X348420Y172609I1415J1416D01*
G01Y196466D01*
G02X351153Y203064I9331J0D01*
G01X391385Y243295D01*
G02X394500Y244585I3115J-3116D01*
G01X399092D01*
G02X401562Y243562I0J-3493D01*
G01X401723Y243401D01*
G03X403174Y242800I1451J1451D01*
G01X418697D01*
G03X421881Y244119I0J4503D01*
G01X443881Y266119D01*
G02X447696Y267699I3816J-3817D01*
G01X478837D01*
G03X482347Y269153I0J4964D01*
G01X483596Y270402D01*
G02X486730Y271700I3133J-3133D01*
G01X509499D01*
G03X521031Y276478I-1J16308D01*
G01X538277Y293722D01*
X543850Y299295D01*
G03X544399Y300623I-1330J1327D01*
G01X544400Y300622D01*
Y306033D01*
X544399Y306032D01*
G03X543530Y308130I-2967J0D01*
G01X543080Y308581D01*
X542707Y308955D01*
X542706D01*
X542702Y308959D01*
X542651Y309011D01*
G03X540500Y309900I-2152J-2159D01*
G01X540423D01*
G02X538780Y310580I0J2325D01*
G01X537229Y312131D01*
X537230D01*
G02X536137Y314770I2641J2640D01*
G01Y319000D01*
G03X535555Y320405I-1987J0D01*
G01X534960Y321000D01*
G01X361046Y153666D02*
X360656Y154056D01*
G02X360409Y154652I596J596D01*
G01Y160802D01*
G03X359823Y162217I-2001J0D01*
G01X349926Y172114D01*
G02X349720Y172610I496J497D01*
G01Y196466D01*
G02X352073Y202144I8030J-1D01*
G01X392252Y242323D01*
X392253D01*
X392305Y242375D01*
G02X394501Y243285I2196J-2195D01*
G01X399093D01*
G02X400642Y242643I-1J-2193D01*
G01X400641Y242642D01*
X400803Y242481D01*
Y242482D01*
G03X403175Y241500I2370J2370D01*
G01X418698D01*
G03X422800Y243199I-1J5803D01*
G01X444800Y265199D01*
G02X447697Y266399I2897J-2897D01*
G01X478838D01*
G03X483266Y268233I-1J6264D01*
G01X484516Y269483D01*
G02X486730Y270400I2214J-2214D01*
G01X495141D01*
G02X496031Y269955I11J-1090D01*
G03X496921Y269510I879J645D01*
G01X498121D01*
G03X499011Y269955I11J1090D01*
G02X499901Y270400I879J-645D01*
G01X509500D01*
G03X521951Y275558I-1J17609D01*
G01X528594Y282201D01*
G02X529538Y282515I778J-763D01*
G03X530482Y282830I165J1078D01*
G01X531331Y283679D01*
G03X531646Y284623I-763J779D01*
G02X531960Y285567I1077J166D01*
G01X532809Y286415D01*
G02X533753Y286730I779J-763D01*
G03X534697Y287044I166J1077D01*
G01X535545Y287893D01*
G03X535860Y288837I-762J779D01*
G02X536175Y289781I1077J165D01*
G01X544769Y298375D01*
G03X545700Y300623I-2248J2248D01*
G01Y306032D01*
G03X544450Y309050I-4268J0D01*
G01X544000Y309500D01*
X543627Y309874D01*
X543575Y309927D01*
G03X540500Y311200I-3074J-3075D01*
G01X540424D01*
G02X539700Y311500I0J1024D01*
G01X538150Y313050D01*
G02X537437Y314771I1721J1721D01*
G01Y319000D01*
G02X538019Y320405I1987J0D01*
G01X538614Y321000D01*
G01X1151318Y717518D02*
Y720182D01*
X1149743Y721757D01*
G01X1154434Y714335D02*
X1155635D01*
X1156030Y714730D01*
Y718144D01*
X1154190Y719984D01*
Y720635D01*
G01X1157637Y717463D02*
X1156930Y718170D01*
Y718517D01*
X1155630Y719817D01*
Y724370D01*
G01X1154200Y788900D02*
X1155092Y788008D01*
Y785146D01*
X1155100Y785136D01*
X1155919Y784317D01*
Y778010D01*
X1154550Y776641D01*
Y771808D01*
X1154100Y771358D01*
Y769156D01*
X1152570Y767626D01*
Y762910D01*
X1150000Y760340D01*
Y744261D01*
X1151511Y742750D01*
X1153138D01*
X1155389Y740499D01*
X1155460D01*
X1157000Y738959D01*
Y734500D01*
G01X1162693Y780865D02*
Y779472D01*
X1162700Y779465D01*
Y777315D01*
X1164057Y775958D01*
Y774243D01*
X1165264Y773036D01*
X1166979D01*
X1170000Y770015D01*
Y766139D01*
X1168300Y764439D01*
X1165139D01*
X1163900Y763200D01*
Y760600D01*
X1165061Y759439D01*
X1168100D01*
X1168500Y759039D01*
Y757439D01*
X1168100Y757039D01*
X1166039D01*
X1164733Y755733D01*
Y753267D01*
X1165961Y752039D01*
X1168100D01*
X1168500Y751639D01*
Y736581D01*
X1167700Y735781D01*
Y730832D01*
X1167682Y730814D01*
Y728182D01*
X1167000Y727500D01*
G01X1157581Y714331D02*
X1159298Y716048D01*
Y722838D01*
X1159550Y723090D01*
G01X1154712Y792690D02*
X1156000D01*
X1156392Y792298D01*
Y791300D01*
X1155700Y790608D01*
Y790100D01*
X1156392Y789408D01*
Y785683D01*
X1157220Y784855D01*
Y783779D01*
X1157219Y783778D01*
Y777471D01*
X1155850Y776102D01*
Y771269D01*
X1155400Y770819D01*
Y768617D01*
X1153870Y767087D01*
Y762371D01*
X1151300Y759801D01*
Y744800D01*
X1152050Y744050D01*
X1153677D01*
X1155928Y741799D01*
X1155999D01*
X1158300Y739498D01*
Y736184D01*
X1158600Y735884D01*
Y733190D01*
X1157112Y731702D01*
G01X1165492Y780957D02*
X1164000Y779465D01*
Y777854D01*
X1165357Y776496D01*
Y774782D01*
X1165803Y774336D01*
X1167518D01*
X1171300Y770554D01*
Y765600D01*
X1168839Y763139D01*
X1165678D01*
X1165200Y762661D01*
Y761139D01*
X1165600Y760739D01*
X1168639D01*
X1169800Y759578D01*
Y756900D01*
X1168639Y755739D01*
X1166578D01*
X1166033Y755194D01*
Y753806D01*
X1166500Y753339D01*
X1168639D01*
X1169800Y752178D01*
Y736043D01*
X1169420Y735662D01*
X1169000Y735242D01*
Y729990D01*
X1169282Y729708D01*
G54D15*
X200118Y739409D03*
X190118D03*
X210118D03*
X230118Y729409D03*
Y739409D03*
X220118D03*
X250118D03*
X240118D03*
X260118Y729409D03*
Y739409D03*
X270118Y729409D03*
Y739409D03*
G54D25*
G01X110500Y848500D02*
X107500D01*
X96500Y837500D01*
Y833764D01*
X68906Y806170D01*
X61900D01*
X57772Y802042D01*
Y801504D01*
G01X61492Y803004D02*
X68569D01*
X98892Y833327D01*
Y836729D01*
X108233Y846070D01*
X113070D01*
X115500Y848500D01*
G01X57804Y834720D02*
X59500Y836416D01*
Y861024D01*
X52304Y868220D01*
G01X52000Y872720D02*
Y872524D01*
X61804Y862720D01*
Y834720D01*
G01X105000Y834500D02*
X103000D01*
X88500Y820000D01*
Y776816D01*
X86404Y774720D01*
G01X132500Y559600D02*
Y559500D01*
X130550Y557550D01*
Y513192D01*
X134692Y509050D01*
X143338D01*
X170239Y482149D01*
X188851D01*
X305500Y365500D01*
Y355172D01*
X334722Y325950D01*
X341721D01*
X344121Y323550D01*
X346949D01*
X376768Y293732D01*
X379500Y291000D01*
X395048D01*
X395104Y291056D01*
G01X374000Y293500D02*
X368371D01*
X337421Y324450D01*
X324661D01*
X302000Y347111D01*
Y366878D01*
X188229Y480649D01*
X169617D01*
X142716Y507550D01*
X132450D01*
X124500Y515500D01*
G01X377855Y300110D02*
X375955D01*
X345565Y330500D01*
X338048D01*
X321497Y347050D01*
X320179Y348368D01*
Y361211D01*
X179390Y502000D01*
X175878D01*
X132500Y545378D01*
Y547000D01*
G01Y556000D02*
X142500Y546000D01*
Y541500D01*
X161275Y522725D01*
Y521272D01*
X162417Y520130D01*
X163870D01*
X178000Y506000D01*
X179634D01*
X336000Y349634D01*
Y338500D01*
X341000Y333500D01*
X347500D01*
X377000Y304000D01*
X379380D01*
X385880Y297500D01*
X404313D01*
X408656Y293157D01*
Y291500D01*
G01X132500Y551500D02*
X140500Y543500D01*
Y539500D01*
X176500Y503500D01*
X180012D01*
X323362Y360150D01*
Y351550D01*
X324679Y350233D01*
Y346821D01*
X339500Y332000D01*
X346500D01*
X376000Y302500D01*
X378758D01*
X385758Y295500D01*
X403555D01*
X405555Y293500D01*
G01X424023Y320783D02*
Y319802D01*
X422905Y318684D01*
Y317906D01*
X418749Y313750D01*
X416550D01*
X415450Y314850D01*
X400815D01*
X393165Y322500D01*
X387738D01*
X194500Y515738D01*
Y532134D01*
X187000Y539634D01*
Y551000D01*
X177943Y560057D01*
Y560746D01*
X176801Y561888D01*
X172234D01*
X145172Y588950D01*
X127950D01*
X126500Y587500D01*
G01X424605Y330117D02*
Y323310D01*
X426205Y321710D01*
Y317316D01*
X420639Y311750D01*
X394244D01*
X191500Y514494D01*
Y530890D01*
X184000Y538390D01*
Y543746D01*
X143296Y584450D01*
X126500D01*
X125050Y583000D01*
G01X419913Y318051D02*
Y316329D01*
X418334Y314750D01*
X416966D01*
X415865Y315850D01*
X401230D01*
X395500Y321580D01*
Y322962D01*
X392092Y326370D01*
X391580D01*
X390934Y327016D01*
X390589D01*
X378383Y339222D01*
X376827D01*
X196000Y520049D01*
Y532756D01*
X188745Y540011D01*
Y555068D01*
X181363Y562450D01*
X178575D01*
X173004Y568021D01*
X169019D01*
X146183Y590857D01*
X124623D01*
X121685Y587919D01*
G01X381500Y297000D02*
X376187D01*
X345737Y327450D01*
X335344D01*
X307000Y355794D01*
Y372268D01*
X195619Y483649D01*
X170861D01*
X143510Y511000D01*
X135500D01*
G01X456055Y338000D02*
X457753Y336302D01*
Y325653D01*
X435600Y303500D01*
X431000D01*
X427250Y299750D01*
X385752D01*
X380002Y305500D01*
X379053D01*
X362005Y322548D01*
Y325182D01*
X346500Y340687D01*
Y341256D01*
X179500Y508256D01*
Y509056D01*
X144000Y544556D01*
Y558000D01*
X136000Y566000D01*
G01X140500Y568000D02*
X148500Y560000D01*
Y542500D01*
X181000Y510000D01*
Y508878D01*
X364000Y325878D01*
Y322675D01*
X379675Y307000D01*
X381500D01*
X387250Y301250D01*
X426628D01*
X430378Y305000D01*
X434978D01*
X439979Y310001D01*
X440001D01*
X440500Y310500D01*
X441185D01*
X453873Y323188D01*
Y336182D01*
X452055Y338000D01*
G01X136500Y569700D02*
X136750Y569950D01*
X141308D01*
X150000Y561258D01*
Y560000D01*
X168389Y541611D01*
Y525111D01*
X182500Y511000D01*
Y510000D01*
X365500Y327000D01*
Y323297D01*
X380297Y308500D01*
X383000D01*
X388750Y302750D01*
X426006D01*
X429756Y306500D01*
X434000D01*
X442750Y315250D01*
Y318811D01*
X442985Y319046D01*
Y321684D01*
X442640Y322029D01*
Y332085D01*
X444555Y334000D01*
G01X133500Y582500D02*
X143124D01*
X182500Y543124D01*
Y530000D01*
X190000Y522500D01*
Y513872D01*
X393622Y310250D01*
X420554D01*
X427965Y317661D01*
Y318293D01*
G01X428542Y341928D02*
X426792Y340178D01*
X424458D01*
X422955Y338675D01*
Y333370D01*
X424458Y331867D01*
X425189D01*
X426355Y330701D01*
Y329970D01*
X432673Y323652D01*
Y316599D01*
X431074Y315000D01*
X429000D01*
X421250Y307250D01*
X392378D01*
X187000Y512628D01*
Y514000D01*
X179500Y521500D01*
Y541880D01*
X144480Y576900D01*
X136500D01*
G01Y573300D02*
X137650Y574450D01*
X144808D01*
X161355Y557903D01*
Y553645D01*
X175500Y539500D01*
Y523000D01*
X185500Y513000D01*
Y512006D01*
X391756Y305750D01*
X421872D01*
X424001Y307879D01*
Y308586D01*
X429415Y314000D01*
X431489D01*
X433673Y316184D01*
Y317674D01*
X436098Y320099D01*
Y324374D01*
X430292Y330180D01*
Y330701D01*
X429126Y331867D01*
X428395D01*
X426892Y333370D01*
Y335697D01*
X428542Y337347D01*
Y337991D01*
G01X431023Y317283D02*
X429783D01*
X421250Y308750D01*
X393000D01*
X188500Y513250D01*
Y515000D01*
X181000Y522500D01*
Y542502D01*
X143002Y580500D01*
X136500D01*
G01X424555Y318000D02*
X419305Y312750D01*
X416135D01*
X415535Y313350D01*
X400193D01*
X392543Y321000D01*
X387116D01*
X193000Y515116D01*
Y531512D01*
X185500Y539012D01*
Y544368D01*
X142868Y587000D01*
X134000D01*
G01X441335Y321000D02*
Y317335D01*
X432000Y308000D01*
X429134D01*
X425384Y304250D01*
X389750D01*
X374005Y319995D01*
Y320308D01*
X372863Y321450D01*
X372550D01*
X371505Y322495D01*
Y323308D01*
X370363Y324450D01*
X369550D01*
X367500Y326500D01*
Y327122D01*
X184000Y510622D01*
Y512000D01*
X174000Y522000D01*
Y538615D01*
X151500Y561115D01*
Y565000D01*
X144000Y572500D01*
G01X417650Y316400D02*
X417200Y316850D01*
X406205D01*
X397555Y325500D01*
X395084D01*
X392714Y327870D01*
X392202D01*
X373505Y346567D01*
Y348308D01*
X372363Y349450D01*
X369603D01*
X197500Y521553D01*
Y533378D01*
X190500Y540378D01*
Y558500D01*
X170250Y578750D01*
Y580932D01*
X168932Y582250D01*
X166750D01*
X162500Y586500D01*
X160500D01*
G01X156900D02*
X158850Y588450D01*
X163108D01*
X167558Y584000D01*
X169304D01*
X172000Y581304D01*
Y579500D01*
X192000Y559500D01*
Y541000D01*
X199000Y534000D01*
Y522175D01*
X370175Y351000D01*
X372935D01*
X375500Y348435D01*
Y346694D01*
X392824Y329370D01*
X393336D01*
X395706Y327000D01*
X408504D01*
X416482Y319022D01*
G01X152948Y587000D02*
X153500D01*
X156450Y589950D01*
X163730D01*
X168180Y585500D01*
X169926D01*
X173500Y581926D01*
Y580500D01*
X193775Y560225D01*
Y547725D01*
X209723Y531777D01*
Y513574D01*
X370797Y352500D01*
X373557D01*
X377000Y349057D01*
Y347316D01*
X393446Y330870D01*
X393958D01*
X396828Y328000D01*
X410733D01*
X416950Y321783D01*
G01X424605Y341928D02*
X422467Y339790D01*
X420133D01*
X418918Y338575D01*
Y333907D01*
X417359Y332348D01*
X394602D01*
X394580Y332370D01*
X394068D01*
X378500Y347938D01*
Y349679D01*
X374179Y354000D01*
X373013D01*
X231005Y496008D01*
Y497808D01*
X212500Y516313D01*
Y540000D01*
X198000Y554500D01*
Y558438D01*
X175000Y581438D01*
Y582548D01*
X170548Y587000D01*
X169438D01*
X167469Y588969D01*
G01X198500Y563000D02*
X214500Y547000D01*
Y527197D01*
X315697Y426000D01*
X341500D01*
X360965Y406535D01*
X371710D01*
G01X203000Y564500D02*
Y563267D01*
X338500Y427767D01*
X342232D01*
X360047Y409952D01*
X370575D01*
G01X216500Y516000D02*
X217500D01*
X238000Y495500D01*
X243000D01*
X266000Y472500D01*
Y468500D01*
X314500Y420000D01*
X337000D01*
X353500Y403500D01*
Y401000D01*
X361500Y393000D01*
Y374000D01*
X364500Y371000D01*
X386500D01*
X390000Y367500D01*
Y366000D01*
X393000Y363000D01*
X395000D01*
X402500Y355500D01*
X430000D01*
X434000Y351500D01*
X449500D01*
X451530Y349470D01*
X452165D01*
G01X243755Y490890D02*
Y485380D01*
X363855Y365280D01*
X368432D01*
X369515Y364197D01*
Y363782D01*
X391801Y341496D01*
X403255D01*
X406760Y337991D01*
X412794D01*
G01X296200Y94400D02*
X298400D01*
X300250Y96250D01*
X303303D01*
X305800Y93753D01*
X332505D01*
X334950Y91308D01*
Y90331D01*
X355431Y69850D01*
X372564D01*
X375726Y73012D01*
X470012D01*
X497000Y100000D01*
X523617D01*
X570617Y147000D01*
X685500D01*
X691500Y153000D01*
X798753D01*
X826453Y180700D01*
X959900D01*
G01X975007Y194300D02*
X971800Y191093D01*
Y189600D01*
X960400Y178200D01*
X828700D01*
X801500Y151000D01*
X800006D01*
X799706Y150700D01*
X692453D01*
X686453Y144700D01*
X571570D01*
X497582Y70712D01*
X378212D01*
X375050Y67550D01*
X354478D01*
X352028Y70000D01*
X342242D01*
X332100Y80142D01*
Y87158D01*
X327805Y91453D01*
X304847D01*
X302000Y94300D01*
G01X339888Y586388D02*
Y580333D01*
X329055Y569500D01*
G01X395104Y291056D02*
X395200Y290960D01*
Y290405D01*
X396605Y289000D01*
X410000D01*
X415711Y294711D01*
X416187D01*
G01X387515Y365500D02*
X387519Y365496D01*
Y365490D01*
X387524Y365485D01*
Y360339D01*
X395613Y352250D01*
X398576D01*
X399146Y351680D01*
X422575D01*
X424453Y349802D01*
X424605D01*
G01X428542Y389174D02*
X426468Y387100D01*
X419855D01*
X418855Y388100D01*
Y397700D01*
X417455Y399100D01*
X415555D01*
X414755Y399900D01*
Y426300D01*
X413755Y427300D01*
Y432200D01*
X395755Y450200D01*
Y451300D01*
X392555Y454500D01*
X386055D01*
G01X392500Y718500D02*
X397000D01*
X404500Y711000D01*
X460500D01*
X591000Y580500D01*
Y469500D01*
X571000Y449500D01*
Y372000D01*
X566430Y367430D01*
Y366500D01*
G01X564215Y369339D02*
X566000Y371124D01*
Y447329D01*
X588950Y470279D01*
Y578758D01*
X459182Y708526D01*
X401974D01*
X396000Y714500D01*
G01X539714Y179150D02*
X538625D01*
X538125Y178650D01*
Y173885D01*
X537625Y173385D01*
X535714D01*
X535329Y173770D01*
Y178459D01*
X534638Y179150D01*
X528582D01*
X527940Y179792D01*
X526842D01*
X525950Y178900D01*
X524481D01*
X523471Y179910D01*
Y180573D01*
X524506Y181608D01*
Y183226D01*
X523982Y183750D01*
X520698D01*
X520198Y183250D01*
Y181600D01*
X519698Y181100D01*
X518698D01*
X518198Y181600D01*
Y183250D01*
X517698Y183750D01*
X516698D01*
X516198Y183250D01*
Y181600D01*
X515698Y181100D01*
X514698D01*
X514198Y181600D01*
Y183250D01*
X513698Y183750D01*
X512698D01*
X512198Y183250D01*
Y181600D01*
X511698Y181100D01*
X510698D01*
X510198Y181600D01*
Y183250D01*
X509698Y183750D01*
X508698D01*
X508198Y183250D01*
Y181600D01*
X507698Y181100D01*
X506698D01*
X506198Y181600D01*
Y183250D01*
X505698Y183750D01*
X486162D01*
X483448Y186464D01*
Y187170D01*
X483704Y187425D01*
Y188131D01*
X482995Y188840D01*
X482289D01*
X482033Y188585D01*
X481327D01*
X480618Y189294D01*
Y190000D01*
X480874Y190255D01*
Y190961D01*
X480165Y191670D01*
X479459D01*
X479203Y191415D01*
X478497D01*
X477788Y192124D01*
Y192830D01*
X478044Y193085D01*
Y193791D01*
X477335Y194500D01*
X476629D01*
X476373Y194245D01*
X475667D01*
X474958Y194954D01*
Y195660D01*
X475214Y195915D01*
Y196621D01*
X474505Y197330D01*
X473799D01*
X473543Y197075D01*
X472837D01*
X471632Y198280D01*
X460236D01*
X457766Y200750D01*
X455795D01*
X454549Y201996D01*
X452807D01*
X452307Y201496D01*
Y199488D01*
X453296Y198499D01*
Y196450D01*
X452796Y195950D01*
X451645D01*
X450679Y194984D01*
Y192320D01*
X452050Y190949D01*
Y187358D01*
X451550Y186858D01*
X439769D01*
X439269Y187358D01*
Y195036D01*
X439769Y195536D01*
X441747D01*
X442247Y195036D01*
Y189838D01*
X442747Y189338D01*
X444602D01*
X445102Y189838D01*
Y191780D01*
X445896Y192574D01*
Y197084D01*
X446396Y197584D01*
X448354D01*
X449775Y199005D01*
Y204121D01*
X449384Y204512D01*
X445231D01*
X443897Y203178D01*
Y202363D01*
G01X796000Y167600D02*
X793988Y165588D01*
X521412D01*
X517000Y170000D01*
X475587D01*
X470637Y174950D01*
X461550D01*
X459000Y177500D01*
X446699D01*
X443879Y180320D01*
G01X572000Y189000D02*
X574011D01*
X574511Y188500D01*
Y180539D01*
X575011Y180039D01*
X576011D01*
X576511Y180539D01*
Y188500D01*
X577011Y189000D01*
X578011D01*
X578511Y188500D01*
Y180539D01*
X579011Y180039D01*
X580011D01*
X580511Y180539D01*
Y191550D01*
X580011Y192050D01*
X563555D01*
X554655Y183150D01*
X530040D01*
X526039Y187151D01*
X493761D01*
X479121Y201791D01*
X460709D01*
X458500Y204000D01*
X457800D01*
X456250Y205550D01*
X452245D01*
X452207Y205512D01*
X443897D01*
G01X559500Y194000D02*
Y192805D01*
X558045Y191350D01*
X531555D01*
X519108Y203797D01*
X493294D01*
X486591Y210500D01*
X460500D01*
X459181Y211819D01*
X457345D01*
X457278Y211886D01*
X449614D01*
X449114Y212386D01*
Y214426D01*
X447110Y216430D01*
X441993D01*
X441493Y216930D01*
Y217930D01*
X441993Y218430D01*
X446610D01*
X447110Y218930D01*
Y219930D01*
X446610Y220430D01*
X439977D01*
X439477Y219930D01*
Y216930D01*
X438977Y216430D01*
X431122D01*
X430622Y215930D01*
Y214930D01*
X431122Y214430D01*
X446117D01*
X447053Y213494D01*
Y212319D01*
X446553Y211819D01*
X443905D01*
X443897Y211811D01*
G01X550500Y188000D02*
Y187300D01*
X549750Y186550D01*
X548050D01*
X547550Y187050D01*
Y189150D01*
X547050Y189650D01*
X546050D01*
X545550Y189150D01*
Y187050D01*
X545050Y186550D01*
X531450D01*
X524068Y193932D01*
X519335D01*
X518835Y194432D01*
Y196389D01*
X518335Y196889D01*
X517335D01*
X516835Y196389D01*
Y194432D01*
X516335Y193932D01*
X515335D01*
X514835Y194432D01*
Y196389D01*
X514335Y196889D01*
X513335D01*
X512835Y196389D01*
Y194432D01*
X512335Y193932D01*
X511335D01*
X510835Y194432D01*
Y196389D01*
X510335Y196889D01*
X509335D01*
X508835Y196389D01*
Y194432D01*
X508335Y193932D01*
X507335D01*
X506835Y194432D01*
Y196389D01*
X506335Y196889D01*
X505335D01*
X504835Y196389D01*
Y194432D01*
X504335Y193932D01*
X503335D01*
X502835Y194432D01*
Y196389D01*
X502335Y196889D01*
X501335D01*
X500835Y196389D01*
Y194432D01*
X500335Y193932D01*
X499335D01*
X498835Y194432D01*
Y196389D01*
X498335Y196889D01*
X497335D01*
X496835Y196389D01*
Y194432D01*
X496335Y193932D01*
X494477D01*
X481720Y206689D01*
X476953D01*
X476453Y206189D01*
Y205691D01*
X475953Y205191D01*
X474953D01*
X474453Y205691D01*
Y206189D01*
X473953Y206689D01*
X472953D01*
X472453Y206189D01*
Y205691D01*
X471953Y205191D01*
X470953D01*
X470453Y205691D01*
Y206189D01*
X469953Y206689D01*
X468953D01*
X468453Y206189D01*
Y205691D01*
X467953Y205191D01*
X466953D01*
X466453Y205691D01*
Y206189D01*
X465953Y206689D01*
X464953D01*
X464453Y206189D01*
Y205691D01*
X463953Y205191D01*
X462237D01*
X461125Y206303D01*
X460697D01*
X458550Y208450D01*
X455663D01*
X455163Y207950D01*
Y207050D01*
X454663Y206550D01*
X453663D01*
X453163Y207050D01*
Y207950D01*
X452663Y208450D01*
X451663D01*
X451163Y207950D01*
Y207050D01*
X450663Y206550D01*
X449663D01*
X449163Y207050D01*
Y210030D01*
X448663Y210530D01*
X447736D01*
X447236Y210030D01*
Y207012D01*
X446736Y206512D01*
X445330D01*
X443897Y207945D01*
Y208662D01*
G01X555500Y194000D02*
X554550Y193050D01*
X532260D01*
X519812Y205498D01*
X518404D01*
X518403Y205497D01*
X493999D01*
X487296Y212200D01*
X462092D01*
X459173Y215119D01*
X457299D01*
X455066Y212886D01*
X452069D01*
X448428Y216527D01*
Y220994D01*
X447894Y221528D01*
X435419D01*
X434919Y222028D01*
Y223625D01*
X435419Y224125D01*
X449524D01*
X449538Y224139D01*
X452946D01*
X453833Y223252D01*
Y221708D01*
X453333Y221208D01*
X451310D01*
X450810Y220708D01*
Y217696D01*
X452906Y215600D01*
X453829D01*
G01X587175Y202525D02*
X586150Y203550D01*
Y209468D01*
X582952Y212666D01*
X582244D01*
X581578Y212000D01*
X580870D01*
X580163Y212707D01*
Y213415D01*
X580829Y214081D01*
Y214789D01*
X580122Y215496D01*
X579414D01*
X578748Y214830D01*
X578040D01*
X577333Y215537D01*
Y216245D01*
X577999Y216911D01*
Y217619D01*
X577292Y218326D01*
X576584D01*
X575918Y217660D01*
X575210D01*
X574503Y218367D01*
Y219075D01*
X575169Y219741D01*
Y220449D01*
X573965Y221653D01*
X545381D01*
X543295Y223739D01*
X497402D01*
X493069Y228072D01*
X464013D01*
X459635Y232450D01*
X448979D01*
X445229Y228700D01*
X443722D01*
X443072Y228050D01*
X437979D01*
X436529Y229500D01*
G01X583325Y208500D02*
X581963D01*
X570510Y219953D01*
X562974D01*
X562474Y219453D01*
Y214046D01*
X561974Y213546D01*
X560974D01*
X560474Y214046D01*
Y219453D01*
X559974Y219953D01*
X544011D01*
X541922Y222039D01*
X496697D01*
X492364Y226372D01*
X462628D01*
X457550Y231450D01*
X449394D01*
X445644Y227700D01*
X444722D01*
X443361Y226339D01*
X443113D01*
G01X439980Y232126D02*
X445825D01*
X448849Y235150D01*
X462194D01*
X465872Y231472D01*
X496175D01*
X500508Y227139D01*
X546824D01*
X546938Y227253D01*
X548554D01*
X548689Y227118D01*
X573665D01*
X591000Y209783D01*
Y199500D01*
X591413Y199087D01*
G01X585325Y198000D02*
X585408D01*
X589125Y201717D01*
Y209253D01*
X575025Y223353D01*
X562971D01*
X562471Y223853D01*
Y224918D01*
X561971Y225418D01*
X560971D01*
X560471Y224918D01*
Y223853D01*
X559971Y223353D01*
X558971D01*
X558471Y223853D01*
Y224918D01*
X557971Y225418D01*
X556971D01*
X556471Y224918D01*
Y223853D01*
X555971Y223353D01*
X554971D01*
X554471Y223853D01*
Y224918D01*
X553971Y225418D01*
X552971D01*
X552471Y224918D01*
Y223853D01*
X551971Y223353D01*
X546086D01*
X544000Y225439D01*
X498107D01*
X493774Y229772D01*
X465167D01*
X461489Y233450D01*
X448564D01*
X444814Y229700D01*
X441379D01*
G01X583204Y236805D02*
X581799Y235400D01*
X578454D01*
X577548Y236306D01*
X563823D01*
X560689Y233172D01*
X532589D01*
X532089Y232672D01*
Y229339D01*
X531589Y228839D01*
X530589D01*
X530089Y229339D01*
Y232672D01*
X529589Y233172D01*
X528589D01*
X528089Y232672D01*
Y229339D01*
X527589Y228839D01*
X526589D01*
X526089Y229339D01*
Y232672D01*
X525589Y233172D01*
X518726D01*
X518226Y232672D01*
Y229339D01*
X517726Y228839D01*
X516726D01*
X516226Y229339D01*
Y232672D01*
X515726Y233172D01*
X514726D01*
X514226Y232672D01*
Y229339D01*
X513726Y228839D01*
X512726D01*
X512226Y229339D01*
Y232672D01*
X511726Y233172D01*
X510726D01*
X510226Y232672D01*
Y229339D01*
X509726Y228839D01*
X508726D01*
X508226Y229339D01*
Y232672D01*
X507726Y233172D01*
X506726D01*
X506226Y232672D01*
Y229339D01*
X505726Y228839D01*
X504726D01*
X504226Y229339D01*
Y232672D01*
X503726Y233172D01*
X466577D01*
X465378Y234372D01*
X462899Y236850D01*
X449134D01*
X446060Y233776D01*
X438649D01*
X437112Y232239D01*
G01X463371Y290371D02*
X458500Y295242D01*
Y298000D01*
X455500Y301000D01*
X432500D01*
G01X1390004Y122600D02*
X1394600D01*
X1396000Y124000D01*
Y684000D01*
X1327250Y752750D01*
Y843079D01*
X1313379Y856950D01*
X1242499D01*
X1163950Y935499D01*
Y935501D01*
X1163550Y935901D01*
Y959415D01*
X1163950Y959815D01*
Y961433D01*
X1162808Y962575D01*
X1161192D01*
X1160742Y962125D01*
X1083945D01*
X1068500Y946680D01*
Y837000D01*
X1053500Y822000D01*
X1043051D01*
X997000Y775949D01*
Y771700D01*
X984206Y758906D01*
X914718D01*
X832308Y841316D01*
Y866570D01*
X828368Y870510D01*
X815490D01*
X761500Y924500D01*
X441000D01*
X432000Y933500D01*
G01X458429Y175590D02*
Y172975D01*
X459179Y172225D01*
Y155668D01*
X465697Y149150D01*
X476183D01*
X476483Y149450D01*
X477879D01*
X487379Y158950D01*
X801450D01*
X830000Y187500D01*
X958500D01*
G01X528500Y172000D02*
Y169000D01*
X528000Y168500D01*
X522000D01*
X520284Y170216D01*
Y175500D01*
X519784Y176000D01*
X502473D01*
X501973Y175500D01*
Y174500D01*
X502473Y174000D01*
X517784D01*
X518284Y173500D01*
Y172500D01*
X517784Y172000D01*
X490204D01*
X489704Y172500D01*
Y173500D01*
X490204Y174000D01*
X498520D01*
X499020Y174500D01*
Y175500D01*
X498520Y176000D01*
X488204D01*
X487704Y175500D01*
Y172500D01*
X487204Y172000D01*
X484701D01*
X482912Y173789D01*
X481500D01*
X480790Y174499D01*
Y175205D01*
X483439Y177855D01*
Y178561D01*
X482233Y179767D01*
X481527D01*
X478465Y176704D01*
X477759D01*
X477051Y177412D01*
Y178120D01*
X477463Y178532D01*
Y179238D01*
X476218Y180483D01*
X474784D01*
X472633Y182634D01*
X460102D01*
X459500Y183236D01*
X448000D01*
X447500Y183736D01*
Y184831D01*
X448000Y185331D01*
X455429D01*
X455929Y185831D01*
Y187811D01*
X455429Y188311D01*
X453894D01*
X453394Y188811D01*
Y189811D01*
X453894Y190311D01*
X455429D01*
X455929Y190811D01*
Y192800D01*
G01X561429Y174441D02*
Y168104D01*
X560929Y167604D01*
X549129D01*
X548629Y168104D01*
Y169485D01*
X548129Y169985D01*
X547129D01*
X546629Y169485D01*
Y168104D01*
X546129Y167604D01*
X545129D01*
X544629Y168104D01*
Y169485D01*
X544129Y169985D01*
X543129D01*
X542629Y169485D01*
Y168104D01*
X542129Y167604D01*
X541129D01*
X540629Y168104D01*
Y169485D01*
X540129Y169985D01*
X539129D01*
X538629Y169485D01*
Y168104D01*
X538129Y167604D01*
X537129D01*
X536629Y168104D01*
Y169485D01*
X536129Y169985D01*
X535129D01*
X534629Y169485D01*
Y168104D01*
X534129Y167604D01*
X532429D01*
X531929Y168104D01*
Y175000D01*
X531429Y175500D01*
X523071D01*
X520871Y177700D01*
X503735D01*
X501085Y180350D01*
X497412D01*
X496912Y179850D01*
Y178200D01*
X496412Y177700D01*
X495412D01*
X494912Y178200D01*
Y179850D01*
X494412Y180350D01*
X493412D01*
X492912Y179850D01*
Y178200D01*
X492412Y177700D01*
X491412D01*
X490912Y178200D01*
Y179850D01*
X490412Y180350D01*
X489412D01*
X488912Y179850D01*
Y178200D01*
X488412Y177700D01*
X487412D01*
X486912Y178200D01*
Y179850D01*
X486412Y180350D01*
X484712D01*
X477216Y187846D01*
X476508D01*
X473736Y185074D01*
X473028D01*
X472321Y185781D01*
Y186489D01*
X475093Y189261D01*
Y189969D01*
X473889Y191173D01*
X473181D01*
X471988Y189980D01*
X471280D01*
X470573Y190687D01*
Y191395D01*
X471766Y192588D01*
Y193296D01*
X470562Y194500D01*
X460807D01*
X460307Y194000D01*
Y193000D01*
X460807Y192500D01*
X463329D01*
X463829Y192000D01*
Y191000D01*
X463329Y190500D01*
X460776D01*
X460276Y190000D01*
Y189000D01*
X460776Y188500D01*
X467594D01*
X468094Y188000D01*
Y185350D01*
X467594Y184850D01*
X460913D01*
X458200Y187563D01*
Y194000D01*
X457700Y194500D01*
X456729D01*
X456229Y195000D01*
Y196700D01*
G01X454329Y199800D02*
X455200D01*
X455500Y199500D01*
X457500D01*
X460800Y196200D01*
X471267D01*
X485417Y182050D01*
X501790D01*
X504440Y179400D01*
X521576D01*
X523776Y177200D01*
X532134D01*
X533629Y175705D01*
Y172262D01*
X534206Y171685D01*
X539951D01*
X540451Y172185D01*
Y176700D01*
X540951Y177200D01*
X541951D01*
X542451Y176700D01*
Y172185D01*
X542951Y171685D01*
X543951D01*
X544451Y172185D01*
Y176700D01*
X544951Y177200D01*
X545951D01*
X546451Y176700D01*
Y172185D01*
X546951Y171685D01*
X547951D01*
X548451Y172185D01*
Y176700D01*
X548951Y177200D01*
X551167D01*
X551667Y176700D01*
Y169804D01*
X552167Y169304D01*
X553167D01*
X553667Y169804D01*
Y176700D01*
X554167Y177200D01*
X555167D01*
X555667Y176700D01*
Y169804D01*
X556167Y169304D01*
X557167D01*
X557667Y169804D01*
Y176700D01*
X558167Y177200D01*
X559867D01*
X560367Y177700D01*
Y178663D01*
X560867Y179163D01*
X561867D01*
X562367Y178663D01*
Y176522D01*
X562867Y176022D01*
X563867D01*
X564367Y176522D01*
Y178663D01*
X564867Y179163D01*
X565867D01*
X566367Y178663D01*
Y176553D01*
X566867Y176053D01*
X570898D01*
X571398Y176553D01*
Y183602D01*
G01X560500Y186000D02*
Y186571D01*
X561000Y187071D01*
X568703D01*
X569203Y186571D01*
Y181950D01*
X568703Y181450D01*
X567003D01*
X566503Y181950D01*
Y184174D01*
X566003Y184674D01*
X565003D01*
X564503Y184174D01*
Y181950D01*
X564003Y181450D01*
X563003D01*
X562503Y181950D01*
Y183091D01*
X562003Y183591D01*
X561003D01*
X560503Y183091D01*
Y181950D01*
X560003Y181450D01*
X558241D01*
X557741Y180950D01*
Y179400D01*
X557241Y178900D01*
X556241D01*
X555741Y179400D01*
Y180950D01*
X555241Y181450D01*
X554241D01*
X553741Y180950D01*
Y179400D01*
X553241Y178900D01*
X552241D01*
X551741Y179400D01*
Y180950D01*
X551241Y181450D01*
X550241D01*
X549741Y180950D01*
Y179400D01*
X549241Y178900D01*
X548241D01*
X547741Y179400D01*
Y180950D01*
X547241Y181450D01*
X546241D01*
X545741Y180950D01*
Y179400D01*
X545241Y178900D01*
X544241D01*
X543741Y179400D01*
Y180950D01*
X543241Y181450D01*
X529039D01*
X525038Y185451D01*
X488789D01*
X486187Y188053D01*
Y188759D01*
X487615Y190186D01*
Y190892D01*
X486906Y191601D01*
X486200D01*
X484772Y190174D01*
X484066D01*
X483357Y190883D01*
Y191589D01*
X484785Y193016D01*
Y193722D01*
X484076Y194431D01*
X483370D01*
X481942Y193004D01*
X481236D01*
X480527Y193713D01*
Y194419D01*
X481955Y195846D01*
Y196552D01*
X481246Y197261D01*
X480540D01*
X479112Y195834D01*
X478406D01*
X477697Y196543D01*
Y197249D01*
X479125Y198676D01*
Y199382D01*
X478416Y200091D01*
X477710D01*
X476282Y198664D01*
X475576D01*
X474260Y199980D01*
X460520D01*
X458100Y202400D01*
X456479D01*
G01X563100Y194000D02*
X557276Y188176D01*
X556570D01*
X555100Y189650D01*
X554288D01*
X553631Y188995D01*
Y188289D01*
X555155Y186761D01*
Y186055D01*
X553950Y184850D01*
X530745D01*
X526744Y188851D01*
X523484D01*
X522984Y189351D01*
Y191611D01*
X522484Y192111D01*
X521484D01*
X520984Y191611D01*
Y189351D01*
X520484Y188851D01*
X519484D01*
X518984Y189351D01*
Y191611D01*
X518484Y192111D01*
X517484D01*
X516984Y191611D01*
Y189351D01*
X516484Y188851D01*
X515484D01*
X514984Y189351D01*
Y191611D01*
X514484Y192111D01*
X513484D01*
X512984Y191611D01*
Y189351D01*
X512484Y188851D01*
X511484D01*
X510984Y189351D01*
Y191611D01*
X510484Y192111D01*
X509484D01*
X508984Y191611D01*
Y189351D01*
X508484Y188851D01*
X507484D01*
X506984Y189351D01*
Y191611D01*
X506484Y192111D01*
X505484D01*
X504984Y191611D01*
Y189351D01*
X504484Y188851D01*
X503484D01*
X502984Y189351D01*
Y191611D01*
X502484Y192111D01*
X501484D01*
X500984Y191611D01*
Y189351D01*
X500484Y188851D01*
X499484D01*
X498984Y189351D01*
Y191611D01*
X498484Y192111D01*
X497484D01*
X496984Y191611D01*
Y189351D01*
X496484Y188851D01*
X494466D01*
X491642Y191675D01*
Y192381D01*
X492279Y193019D01*
Y193725D01*
X491570Y194434D01*
X490864D01*
X490227Y193796D01*
X489521D01*
X488812Y194505D01*
Y195211D01*
X489449Y195849D01*
Y196555D01*
X488740Y197264D01*
X488034D01*
X487397Y196626D01*
X486691D01*
X485982Y197335D01*
Y198041D01*
X486619Y198679D01*
Y199385D01*
X485910Y200094D01*
X485204D01*
X484567Y199456D01*
X483861D01*
X483152Y200165D01*
Y200871D01*
X483789Y201509D01*
Y202215D01*
X483080Y202924D01*
X482374D01*
X481737Y202286D01*
X481031D01*
X479826Y203491D01*
X461532D01*
X458223Y206800D01*
X457729D01*
G01X545000Y195000D02*
X545250Y194750D01*
X551925D01*
X553125Y195950D01*
X554855D01*
X555355Y196450D01*
Y197694D01*
X555855Y198194D01*
X556855D01*
X557355Y197694D01*
Y196450D01*
X557855Y195950D01*
X558855D01*
X559355Y196450D01*
Y197694D01*
X559855Y198194D01*
X560855D01*
X561355Y197694D01*
Y196450D01*
X561855Y195950D01*
X563555D01*
X564055Y196450D01*
Y197583D01*
X564555Y198083D01*
X565555D01*
X566055Y197583D01*
Y194250D01*
X566555Y193750D01*
X570822D01*
X571322Y194250D01*
Y198850D01*
X570822Y199350D01*
X568487D01*
X567729Y200108D01*
X551359D01*
X550859Y199608D01*
Y197005D01*
X550359Y196505D01*
X549359D01*
X548859Y197005D01*
Y199608D01*
X548359Y200108D01*
X547359D01*
X546859Y199608D01*
Y198303D01*
X546359Y197803D01*
X545359D01*
X544859Y198303D01*
Y199608D01*
X544359Y200108D01*
X542659D01*
X537551Y195000D01*
X532715D01*
X520517Y207198D01*
X517699D01*
X517698Y207197D01*
X494704D01*
X488001Y213900D01*
X462797D01*
X460578Y216119D01*
X456910D01*
X453729Y219300D01*
G01X448840Y225775D02*
X448078Y226537D01*
Y227626D01*
X448578Y228126D01*
X452863D01*
X453363Y227626D01*
Y225137D01*
X455958Y222542D01*
Y221836D01*
X455122Y220998D01*
Y220290D01*
X455830Y219584D01*
X456538D01*
X457373Y220421D01*
X458079D01*
X458981Y219519D01*
X466021D01*
X466540Y219000D01*
X488706D01*
X488707Y219001D01*
X490115D01*
X496716Y212400D01*
X525636D01*
X526136Y212900D01*
Y214595D01*
X526636Y215095D01*
X528684D01*
X529184Y214595D01*
Y214134D01*
X529684Y213634D01*
X530684D01*
X531184Y214134D01*
Y214595D01*
X531684Y215095D01*
X539246D01*
X547976Y206365D01*
Y202519D01*
X548476Y202019D01*
X568223D01*
X569192Y201050D01*
X571277D01*
X571777Y201550D01*
Y202056D01*
X572277Y202556D01*
X575836D01*
X575842Y202550D01*
X577760D01*
X578254Y202056D01*
Y194669D01*
X577754Y194169D01*
X573408D01*
X573022Y194555D01*
Y198014D01*
X573408Y198400D01*
X575500D01*
G01X542500Y188500D02*
Y189109D01*
X542000Y189609D01*
X539032D01*
X538532Y189109D01*
Y188750D01*
X538032Y188250D01*
X536950D01*
X536450Y188750D01*
Y189150D01*
X535950Y189650D01*
X534950D01*
X534450Y189150D01*
Y188750D01*
X533950Y188250D01*
X532250D01*
X524868Y195632D01*
X522475D01*
X522121Y195986D01*
Y197050D01*
X522475Y197404D01*
Y198025D01*
X521827Y198673D01*
X516884D01*
X516384Y199173D01*
Y201597D01*
X515884Y202097D01*
X514884D01*
X514384Y201597D01*
Y199173D01*
X513884Y198673D01*
X512884D01*
X512384Y199173D01*
Y201597D01*
X511884Y202097D01*
X510884D01*
X510384Y201597D01*
Y199173D01*
X509884Y198673D01*
X508884D01*
X508384Y199173D01*
Y201597D01*
X507884Y202097D01*
X506884D01*
X506384Y201597D01*
Y199173D01*
X505884Y198673D01*
X504884D01*
X504384Y199173D01*
Y201597D01*
X503884Y202097D01*
X502884D01*
X502384Y201597D01*
Y199173D01*
X501884Y198673D01*
X500884D01*
X500384Y199173D01*
Y201597D01*
X499884Y202097D01*
X498884D01*
X498384Y201597D01*
Y199173D01*
X497884Y198673D01*
X496884D01*
X496384Y199173D01*
Y201597D01*
X495884Y202097D01*
X494884D01*
X494384Y201597D01*
Y199113D01*
X494700Y198797D01*
Y197827D01*
X494200Y197327D01*
X493487D01*
X490980Y199834D01*
Y200585D01*
X491954Y201559D01*
Y202267D01*
X491247Y202974D01*
X490539D01*
X489565Y202000D01*
X488857D01*
X488150Y202707D01*
Y203415D01*
X489124Y204389D01*
Y205097D01*
X488417Y205804D01*
X487709D01*
X486735Y204830D01*
X486027D01*
X485082Y205775D01*
Y206549D01*
X485662Y207129D01*
Y208000D01*
X485162Y208500D01*
X464233D01*
X463492Y207759D01*
X462074D01*
X461333Y208500D01*
X460050D01*
X458500Y210050D01*
X452579D01*
X452393Y210236D01*
G01X533441Y211775D02*
Y212895D01*
X533941Y213395D01*
X538541D01*
X541179Y210757D01*
Y209458D01*
X540679Y208958D01*
X533029D01*
X532529Y208458D01*
Y207458D01*
X533029Y206958D01*
X544978D01*
X545916Y206020D01*
Y202463D01*
X545336Y201883D01*
X544175D01*
X543656Y202402D01*
Y204470D01*
X543168Y204958D01*
X533029D01*
X532529Y204458D01*
Y203458D01*
X533029Y202958D01*
X540679D01*
X541179Y202458D01*
Y201033D01*
X540404Y200258D01*
X532267D01*
X528932Y203593D01*
Y204301D01*
X530646Y206015D01*
Y206723D01*
X529939Y207430D01*
X529231D01*
X527517Y205716D01*
X526809D01*
X526102Y206423D01*
Y207131D01*
X529490Y210519D01*
Y211227D01*
X528783Y211934D01*
X528075D01*
X524687Y208546D01*
X523979D01*
X521825Y210700D01*
X496011D01*
X489411Y217300D01*
X465835D01*
X465316Y217819D01*
X457848D01*
X457798Y217769D01*
G01X455429Y227500D02*
X456457D01*
X461038Y222919D01*
X491007D01*
X495287Y218639D01*
X540512D01*
X551614Y207537D01*
Y207489D01*
X555025Y204078D01*
X568913D01*
X570468Y205633D01*
X571176D01*
X572439Y204371D01*
X573145D01*
X573853Y205079D01*
Y205785D01*
X573660Y205978D01*
Y208894D01*
X574160Y209394D01*
X576201D01*
X579588Y206007D01*
Y204750D01*
X579088Y204250D01*
X576900D01*
X576650Y204500D01*
G01X583500D02*
X572950Y215050D01*
X566271D01*
X565163Y213942D01*
Y209850D01*
X562782Y207469D01*
X554087D01*
X552882Y208674D01*
Y209382D01*
X555895Y212395D01*
Y213103D01*
X555188Y213810D01*
X554480D01*
X551467Y210797D01*
X550759D01*
X541217Y220339D01*
X495992D01*
X491659Y224672D01*
X461690D01*
X456562Y229800D01*
X451929D01*
G01X549926Y204000D02*
X549914Y204012D01*
Y206832D01*
X539949Y216797D01*
X524100D01*
X523600Y216297D01*
Y214921D01*
X523100Y214421D01*
X522100D01*
X521600Y214921D01*
Y216297D01*
X521100Y216797D01*
X520100D01*
X519600Y216297D01*
Y214921D01*
X519100Y214421D01*
X518100D01*
X517600Y214921D01*
Y216297D01*
X517100Y216797D01*
X516100D01*
X515600Y216297D01*
Y214921D01*
X515100Y214421D01*
X514100D01*
X513600Y214921D01*
Y216297D01*
X513100Y216797D01*
X512100D01*
X511600Y216297D01*
Y214921D01*
X511100Y214421D01*
X510100D01*
X509600Y214921D01*
Y216297D01*
X509100Y216797D01*
X508100D01*
X507600Y216297D01*
Y214921D01*
X507100Y214421D01*
X506100D01*
X505600Y214921D01*
Y216297D01*
X505100Y216797D01*
X504100D01*
X503600Y216297D01*
Y214921D01*
X503100Y214421D01*
X502100D01*
X501600Y214921D01*
Y216297D01*
X501100Y216797D01*
X500100D01*
X499600Y216297D01*
Y214921D01*
X499100Y214421D01*
X498100D01*
X497600Y214921D01*
Y216297D01*
X497100Y216797D01*
X494724D01*
X490820Y220701D01*
X488002D01*
X488001Y220700D01*
X467245D01*
X466726Y221219D01*
X460217D01*
X456929Y224507D01*
G01X795500Y163408D02*
X520092D01*
X517000Y166500D01*
X478812D01*
X466676Y154364D01*
Y151212D01*
X466464Y151000D01*
G01X464570Y215750D02*
X464720Y215600D01*
X488706D01*
X495409Y208897D01*
X516993D01*
X516994Y208898D01*
X519812D01*
X519813Y208899D01*
X521221D01*
X533262Y196858D01*
X536979D01*
X537479Y197358D01*
Y197875D01*
G01X957990Y191064D02*
X830064D01*
X800408Y161408D01*
X518092D01*
X515000Y164500D01*
X495929D01*
G01X552954Y315945D02*
X554228Y314671D01*
G02X554724Y313496I-1197J-1198D01*
G01Y313093D01*
G02X553385Y311607I-1494J0D01*
G02X553231Y311600I-145J1486D01*
G01X552731D01*
G02X551577Y312078I0J1631D01*
G01X550050Y313605D01*
G02X549555Y314800I1195J1195D01*
G01Y321000D01*
G02X550301Y322801I2547J0D01*
G01X552323Y324823D01*
G02X553957Y325500I1634J-1634D01*
G01X564733D01*
G03X567750Y326750I-1J4268D01*
G01X568500Y327500D01*
G02X570673Y328400I2173J-2173D01*
G01X572499D01*
G03X579254Y331197I1J9552D01*
G01X595325Y347268D01*
G02X597093Y348000I1768J-1768D01*
G01X627676D01*
G02X628266Y347705I-26J-790D01*
G03X628856Y347410I616J494D01*
G01X630356D01*
G03X630946Y347705I-26J790D01*
G02X631536Y348000I616J-494D01*
G01X633036D01*
G02X633626Y347705I-26J-790D01*
G03X634216Y347410I616J494D01*
G01X635716D01*
G03X636306Y347705I-26J790D01*
G02X636896Y348000I616J-494D01*
G01X638396D01*
G02X638986Y347705I-26J-790D01*
G03X639576Y347410I616J494D01*
G01X641076D01*
G03X641666Y347705I-26J790D01*
G02X642256Y348000I616J-494D01*
G01X646495D01*
G02X647085Y347705I-26J-790D01*
G03X647675Y347410I616J495D01*
G01X649175D01*
G03X649765Y347705I-26J790D01*
G02X650355Y348000I616J-495D01*
G01X651855D01*
G02X652445Y347705I-26J-790D01*
G03X653035Y347410I616J495D01*
G01X654535D01*
G03X655125Y347705I-26J790D01*
G02X655715Y348000I616J-495D01*
G01X657215D01*
G02X657805Y347705I-26J-790D01*
G03X658395Y347410I616J495D01*
G01X659895D01*
G03X660485Y347705I-26J790D01*
G02X661075Y348000I616J-495D01*
G01X680161D01*
G02X680751Y347705I-26J-789D01*
G03X681341Y347410I616J495D01*
G01X682841D01*
G03X683431Y347705I-26J789D01*
G02X684021Y348000I616J-495D01*
G01X685521D01*
G02X686111Y347705I-26J-789D01*
G03X686701Y347410I616J495D01*
G01X688201D01*
G03X688791Y347705I-26J789D01*
G02X689381Y348000I616J-495D01*
G01X690881D01*
G02X691471Y347705I-26J-789D01*
G03X692061Y347410I616J495D01*
G01X693561D01*
G03X694151Y347705I-26J789D01*
G02X694741Y348000I616J-495D01*
G01X722106D01*
G02X726273Y346274I0J-5893D01*
G01X728813Y343734D01*
G03X733000Y342000I4187J4188D01*
G01X1187019D01*
G02X1189127Y341127I0J-2981D01*
G03X1191366Y340200I2238J2239D01*
G01X1196365D01*
G03X1197494Y340668I-1J1598D01*
G01X1197913Y341087D01*
G03X1198430Y342335I-1248J1248D01*
G01Y343000D01*
G02X1198665Y343569I804J1D01*
G01X1199685Y344588D01*
G01X556889Y308070D02*
Y308411D01*
G03X554800Y310500I-2089J0D01*
G01X552730D01*
G02X550799Y311300I0J2731D01*
G01X549272Y312827D01*
G02X548455Y314799I1973J1973D01*
G01Y321000D01*
G02X549523Y323579I3648J0D01*
G01X551545Y325601D01*
G02X553956Y326600I2412J-2412D01*
G01X564732D01*
G03X566972Y327528I0J3168D01*
G01X567722Y328278D01*
G02X570673Y329500I2951J-2951D01*
G01X572500D01*
G03X578476Y331975I0J8452D01*
G01X594547Y348046D01*
G02X597094Y349100I2545J-2546D01*
G01X722106D01*
G02X727051Y347052I0J-6993D01*
G01X729591Y344512D01*
G03X733000Y343100I3409J3409D01*
G01X1187019D01*
G02X1189905Y341905I1J-4081D01*
G03X1191366Y341300I1461J1461D01*
G01X1196364D01*
G03X1196716Y341446I0J498D01*
G01X1197135Y341865D01*
G03X1197330Y342336I-470J470D01*
G01Y343000D01*
G03X1197095Y343569I-804J1D01*
G01X1196075Y344588D01*
G01X560829Y290355D02*
G02X560155Y291982I1627J1627D01*
G01Y309100D01*
G03X559558Y310541I-2038J0D01*
G01X556941Y313158D01*
G02X556055Y315299I2145J2141D01*
G01Y316000D01*
G02X561555Y321500I5500J0D01*
G01X567000D01*
G03X572122Y323621I1J7243D01*
G01X574379Y325879D01*
G02X579500Y328000I5121J-5122D01*
G01X582589D01*
G03X585001Y328999I0J3411D01*
G01X592000Y335998D01*
X592381Y336381D01*
G02X597500Y338501I5118J-5118D01*
G01X597501Y338500D01*
X700257D01*
G02X702904Y337404I1J-3743D01*
G01X703974Y336334D01*
G03X704539Y336100I565J565D01*
G01X1180992D01*
G02X1183190Y335190I1J-3108D01*
G01X1183327Y335053D01*
G03X1185000Y334360I1673J1673D01*
G01X1232200D01*
G02X1237616Y332117I0J-7659D01*
G01X1245755Y323978D01*
G03X1248358Y322900I2603J2603D01*
G01X1251953D01*
G03X1252677Y323200I0J1024D01*
G03X1253177Y324407I-1207J1207D01*
G01Y324500D01*
G01X564764Y298230D02*
G02X565000Y297660I-570J-570D01*
G01Y295000D01*
G02X564886Y294725I-389J0D01*
G01X564559Y294398D01*
X564448Y294288D01*
G02X563450Y293874I-999J998D01*
G02X562455Y294400I355J1876D01*
G01X561855Y295000D01*
G02X561255Y296449I1449J1449D01*
G01Y309100D01*
G03X560336Y311319I-3138J0D01*
G01X557855Y313800D01*
X557721Y313935D01*
G02X557155Y315300I1365J1366D01*
G01Y316000D01*
G02X561555Y320400I4400J0D01*
G01X567000D01*
Y320399D01*
G03X572900Y322843I0J8344D01*
G01X575157Y325101D01*
G02X579500Y326900I4343J-4343D01*
G01X582589D01*
G03X585779Y328221I0J4511D01*
G01X592779Y335221D01*
X593160Y335604D01*
G02X597500Y337401I4339J-4341D01*
G02X597609Y337400I-2J-6138D01*
G01X700257D01*
G02X702126Y336626I0J-2643D01*
G01X703196Y335556D01*
G03X704539Y335000I1343J1344D01*
G01X1180992D01*
G02X1182412Y334412I0J-2008D01*
G01X1182549Y334275D01*
G03X1185000Y333260I2451J2452D01*
G01X1232200D01*
G02X1236838Y331339I0J-6559D01*
G01X1244977Y323200D01*
G03X1248358Y321800I3380J3381D01*
G01X1251410D01*
G02X1252202Y321472I0J-1120D01*
G01X1253177Y320500D01*
G01X711500Y179400D02*
X711300Y179600D01*
X704900D01*
X641000Y243500D01*
X592204D01*
X563704Y272000D01*
G01X576574Y290355D02*
Y292642D01*
G03X575935Y295212I-5486J0D01*
G02X575655Y296339I2124J1126D01*
G01Y308233D01*
G02X576905Y311250I4268J-1D01*
G01X579355Y313700D01*
G03X579955Y315149I-1449J1449D01*
G01Y316368D01*
G02X580755Y318300I2732J0D01*
G01X581955Y319500D01*
G02X584370Y320500I2415J-2415D01*
G01X598197D01*
G03X599472Y321028I0J1803D01*
G01X600222Y321778D01*
G02X602930Y322900I2709J-2709D01*
G01X868369D01*
G02X869712Y322344I0J-1900D01*
G01X870718Y321338D01*
G03X872500Y320600I1782J1782D01*
G01X909769D01*
G03X910334Y320834I0J799D01*
G01X911250Y321750D01*
G02X913666Y322750I2415J-2415D01*
G01X1160501D01*
G02X1163418Y321542I0J-4127D01*
G01X1166176Y318784D01*
G03X1170000Y317200I3824J3824D01*
G01X1222710D01*
G02X1225178Y316178I0J-3490D01*
G01X1225678Y315678D01*
G03X1229403Y314135I3725J3725D01*
G01X1233846D01*
G02X1237293Y312707I0J-4874D01*
G01X1238000Y312000D01*
G03X1239569Y311350I1569J1569D01*
G01X1251820D01*
G03X1252173Y311496I0J500D01*
G01X1253477Y312800D01*
G01X568699Y315945D02*
X570200Y312946D01*
G03X570871Y312723I447J224D01*
G01X570872D01*
X571317Y312947D01*
G03X572055Y314726I-1778J1780D01*
G01Y316501D01*
G02X573194Y319249I3888J-1D01*
G01X574222Y320278D01*
X576222Y322278D01*
G02X580620Y324100I4399J-4399D01*
G01X587500D01*
G03X590913Y325514I0J4826D01*
G01X593627Y328228D01*
G02X596699Y329500I3071J-3072D01*
G01X1168138D01*
G02X1170559Y328497I-1J-3425D01*
G01X1171278Y327778D01*
G02X1171870Y326348I-1430J-1430D01*
G01Y325500D01*
G03X1172244Y324597I1277J0D01*
G01X1173125Y323716D01*
G01X572639Y308070D02*
X571139Y311067D01*
G02X571362Y311738I447J224D01*
G01X571363D01*
X571366Y311740D01*
X571811Y311963D01*
X571956Y312036D01*
G03X572096Y312169I-2420J2687D01*
G03X573155Y314725I-2557J2557D01*
G01Y316500D01*
G02X573972Y318471I2788J-1D01*
G01X575000Y319500D01*
X577000Y321500D01*
G02X580621Y323000I3621J-3621D01*
G01X587500D01*
G03X591691Y324736I0J5927D01*
G01X594405Y327450D01*
G02X596699Y328400I2294J-2294D01*
G01X1168137D01*
G02X1169781Y327719I0J-2325D01*
G01X1170500Y327000D01*
G02X1170770Y326348I-652J-652D01*
G01Y325500D01*
G02X1170396Y324597I-1277J0D01*
G01X1169515Y323716D01*
G01X584449Y315945D02*
X585947Y312947D01*
G02X585723Y312276I-448J-223D01*
G01X585722D01*
X585700Y312266D01*
X585132Y311983D01*
G03X584018Y309501I2203J-2480D01*
G01Y298311D01*
G02X583136Y296180I-3013J-1D01*
G01X580955Y294000D01*
G03Y287344I3328J-3328D01*
G01X582877Y285422D01*
G02X583355Y284268I-1153J-1154D01*
G01Y282400D01*
G03X586679Y274376I11347J0D01*
G01X600233Y260822D01*
X604413Y256643D01*
G03X611999Y253500I7587J7587D01*
G01X698135D01*
G02X699685Y252858I0J-2191D01*
G03X702000Y251899I2315J2315D01*
G01Y251900D01*
X904617D01*
G03X912878Y255322I-1J11684D01*
G01X926528Y268972D01*
G02X932631Y271500I6103J-6103D01*
G01X1172500D01*
G03X1179328Y274328I0J9657D01*
G01X1190584Y285584D01*
G03X1191377Y287499I-1917J1916D01*
G01Y288000D01*
G02X1191684Y288741I1048J0D01*
G01X1192743Y289800D01*
G01X592324Y290355D02*
X592832Y290863D01*
G03Y293168I-1152J1153D01*
G01X592478Y293522D01*
G03X589977I-1250J-1250D01*
G01X589555Y293100D01*
G03Y288800I2150J-2150D01*
G01X592282Y286073D01*
G02X593065Y284182I-1892J-1891D01*
G01Y283227D01*
G03X593405Y282406I1161J0D01*
G01X599810Y276001D01*
Y276000D01*
X606405Y269405D01*
G03X615712Y265550I9307J9307D01*
G01X709595D01*
G02X715322Y263178I0J-8100D01*
G01X717100Y261400D01*
G03X720721Y259900I3621J3621D01*
G01X901440D01*
G03X908200Y262700I0J9560D01*
G01X921182Y275682D01*
G02X930400Y279500I9218J-9219D01*
G01X1172098D01*
G03X1173638Y280138I0J2178D01*
G01X1180000Y286500D01*
X1180439Y286940D01*
G03X1181500Y289500I-2560J2561D01*
G01Y291326D01*
G02X1182722Y294278I4173J1D01*
G01X1183697Y295254D01*
G02X1185500Y296001I1803J-1803D01*
G01Y296000D01*
X1188798D01*
G03X1189388Y296295I-26J790D01*
G02X1189978Y296590I616J-495D01*
G01X1191478D01*
G02X1192068Y296295I-26J-790D01*
G03X1192658Y296000I616J495D01*
G01X1194158D01*
G03X1194748Y296295I-26J790D01*
G02X1195338Y296590I616J-495D01*
G01X1196838D01*
G02X1197428Y296295I-26J-790D01*
G03X1198018Y296000I616J495D01*
G01X1199518D01*
G03X1200108Y296295I-26J790D01*
G02X1200698Y296590I616J-495D01*
G01X1202198D01*
G02X1202788Y296295I-26J-790D01*
G03X1203378Y296000I616J495D01*
G01X1204878D01*
G02X1210605Y293628I0J-8099D01*
G01X1211666Y292567D01*
G03X1212291Y292359I539J577D01*
G02X1212917Y292150I86J-785D01*
G01X1213978Y291089D01*
G02X1214186Y290464I-577J-539D01*
G03X1214395Y289838I786J-86D01*
G01X1215456Y288777D01*
G03X1216082Y288569I539J577D01*
G02X1216707Y288360I85J-785D01*
G01X1217768Y287299D01*
G02X1217977Y286674I-576J-540D01*
G03X1218185Y286048I785J-87D01*
G01X1219246Y284987D01*
G03X1219872Y284779I539J577D01*
G02X1220497Y284570I85J-786D01*
G01X1221558Y283509D01*
G02X1221767Y282884I-576J-540D01*
G03X1221975Y282258I785J-87D01*
G01X1223616Y280617D01*
X1224155Y280079D01*
G03X1227000Y278900I2845J2843D01*
G01X1228499D01*
G03X1229089Y279195I-26J790D01*
G02X1229679Y279490I616J-495D01*
G01X1231179D01*
G02X1231769Y279195I-26J-790D01*
G03X1232359Y278900I616J495D01*
G01X1233859D01*
G03X1234449Y279195I-26J790D01*
G02X1235039Y279490I616J-495D01*
G01X1236539D01*
G02X1237129Y279195I-26J-790D01*
G03X1237719Y278900I616J495D01*
G01X1239219D01*
G03X1239809Y279195I-26J790D01*
G02X1240399Y279490I616J-495D01*
G01X1241899D01*
G02X1242489Y279195I-26J-790D01*
G03X1243079Y278900I616J495D01*
G01X1252204D01*
G03X1254377Y279800I0J3073D01*
G01X1255877Y281300D01*
G03X1257477Y285163I-3862J3862D01*
G01Y290168D01*
G03X1256999Y291322I-1631J0D01*
G01X1256988Y291332D01*
G02X1256968Y291353I299J305D01*
G01X1256967Y291354D01*
G02X1256133Y293399I2091J2045D01*
G01Y294648D01*
G02X1257222Y297278I3719J0D01*
G02X1259224Y298049I1868J-1867D01*
G03X1260577Y299335I65J1286D01*
G01Y299968D01*
G01X596259Y298230D02*
X594403Y296374D01*
G02X593500Y296000I-903J903D01*
G01X592274D01*
G03X589927Y295028I0J-3319D01*
G01X588777Y293878D01*
G03Y288022I2928J-2928D01*
G01X591504Y285295D01*
G02X591965Y284182I-1113J-1113D01*
G01Y283227D01*
G03X592627Y281628I2261J0D01*
G01X598710Y275545D01*
Y275544D01*
X605627Y268627D01*
G03X615712Y264450I10085J10085D01*
G01X709595D01*
G02X714544Y262400I0J-7000D01*
G01X716322Y260622D01*
G03X720720Y258800I4399J4399D01*
G01X901440D01*
G03X908978Y261922I0J10660D01*
G01X921960Y274904D01*
G02X930400Y278400I8440J-8440D01*
G01X1172099D01*
G03X1174416Y279360I-1J3278D01*
G01X1181218Y286162D01*
G03X1182600Y289499I-3339J3338D01*
G01Y291327D01*
G02X1183500Y293500I3073J0D01*
G01X1184475Y294476D01*
G02X1185500Y294900I1024J-1025D01*
G01X1204878D01*
G02X1209827Y292850I0J-6999D01*
G01X1222838Y279839D01*
X1223377Y279301D01*
G03X1227000Y277800I3623J3622D01*
G01X1252204D01*
G03X1255155Y279022I0J4173D01*
G01X1256655Y280522D01*
G03X1258577Y285162I-4640J4640D01*
G01Y290169D01*
G03X1257777Y292100I-2731J0D01*
G01X1257768Y292110D01*
G02X1257233Y293400I1290J1291D01*
G01Y294648D01*
G02X1258000Y296500I2619J0D01*
G02X1259168Y296949I1089J-1090D01*
G02X1260179Y296500I-78J-1539D01*
G01X1260577Y296102D01*
G01X588384Y308070D02*
X586887Y311068D01*
G03X586216Y311292I-447J-223D01*
G01X586215D01*
X585767Y311069D01*
G03X585118Y309502I1567J-1567D01*
G01Y298311D01*
G02X583914Y295402I-4113J-1D01*
G01X581733Y293222D01*
G03Y288122I2550J-2550D01*
G01X583655Y286200D01*
G02X584455Y284269I-1931J-1931D01*
G01Y282401D01*
G03X587457Y275154I10247J-1D01*
G01X601011Y261600D01*
X605191Y257421D01*
G03X612000Y254600I6810J6809D01*
G01X615316D01*
G03X615906Y254895I-26J790D01*
G02X616496Y255190I616J-495D01*
G01X617996D01*
G02X618586Y254895I-26J-790D01*
G03X619176Y254600I616J495D01*
G01X620676D01*
G03X621266Y254895I-26J790D01*
G02X621856Y255190I616J-495D01*
G01X623356D01*
G02X623946Y254895I-26J-790D01*
G03X624536Y254600I616J495D01*
G01X626036D01*
G03X626626Y254895I-26J790D01*
G02X627216Y255190I616J-495D01*
G01X628716D01*
G02X629306Y254895I-26J-790D01*
G03X629896Y254600I616J495D01*
G01X638335D01*
G03X638925Y254895I-26J789D01*
G02X639515Y255190I616J-495D01*
G01X641015D01*
G02X641605Y254895I-26J-789D01*
G03X642195Y254600I616J495D01*
G01X643695D01*
G03X644285Y254895I-26J789D01*
G02X644875Y255190I616J-495D01*
G01X646375D01*
G02X646965Y254895I-26J-789D01*
G03X647555Y254600I616J495D01*
G01X649055D01*
G03X649645Y254895I-26J789D01*
G02X650235Y255190I616J-495D01*
G01X651735D01*
G02X652325Y254895I-26J-789D01*
G03X652915Y254600I616J495D01*
G01X662095D01*
G03X662685Y254895I-26J790D01*
G02X663275Y255190I616J-495D01*
G01X664775D01*
G02X665365Y254895I-26J-790D01*
G03X665955Y254600I616J495D01*
G01X698136D01*
G02X700463Y253636I0J-3291D01*
G03X702000Y253000I1536J1537D01*
G01X904616D01*
G03X912100Y256100I0J10584D01*
G01X925750Y269750D01*
G02X932630Y272600I6881J-6881D01*
G01X1172500D01*
G03X1178550Y275106I0J8556D01*
G01X1189472Y286028D01*
X1189805Y286362D01*
G03X1190277Y287500I-1138J1139D01*
G01Y288000D01*
G03X1189994Y288683I-966J0D01*
G01X1188877Y289800D01*
G01X580514Y298230D02*
G02X579545Y295889I-3310J-1D01*
G01X579355Y295700D01*
G02X578674Y295418I-681J681D01*
G01X577655D01*
G02X576909Y295727I0J1055D01*
G01X576908Y295728D01*
G02X576755Y296340I1151J613D01*
G01Y308232D01*
G02X577683Y310472I3168J0D01*
G01X580133Y312922D01*
G03X581055Y315149I-2227J2226D01*
G01Y316368D01*
G02X581533Y317522I1632J0D01*
G01X582733Y318722D01*
G02X584370Y319400I1637J-1637D01*
G01X598197D01*
G03X600250Y320250I0J2903D01*
G01X601000Y321000D01*
G02X602931Y321800I1931J-1931D01*
G01X868369D01*
G02X868934Y321566I0J-799D01*
G01X869940Y320560D01*
G03X872500Y319500I2560J2561D01*
G01X909769D01*
G03X911112Y320056I0J1900D01*
G01X912028Y320972D01*
G02X913665Y321650I1637J-1637D01*
G01X1160500D01*
G02X1162640Y320763I-1J-3027D01*
G01X1162952Y320452D01*
X1165398Y318006D01*
G03X1170000Y316100I4602J4603D01*
G01X1176067D01*
G02X1176657Y315805I-26J-790D01*
G03X1177247Y315510I616J495D01*
G01X1178747D01*
G03X1179337Y315805I-26J790D01*
G02X1179927Y316100I616J-495D01*
G01X1181427D01*
G02X1182017Y315805I-26J-789D01*
G03X1182607Y315510I616J495D01*
G01X1184107D01*
G03X1184697Y315805I-26J789D01*
G02X1185287Y316100I616J-495D01*
G01X1186787D01*
G02X1187377Y315805I-26J-789D01*
G03X1187967Y315510I616J495D01*
G01X1189467D01*
G03X1190057Y315805I-26J789D01*
G02X1190647Y316100I616J-495D01*
G01X1192147D01*
G02X1192737Y315805I-26J-789D01*
G03X1193327Y315510I616J495D01*
G01X1194827D01*
G03X1195417Y315805I-26J789D01*
G02X1196007Y316100I616J-495D01*
G01X1204474D01*
G02X1205064Y315805I-26J-790D01*
G03X1205654Y315510I616J495D01*
G01X1207154D01*
G03X1207744Y315805I-26J790D01*
G02X1208334Y316100I616J-495D01*
G01X1209834D01*
G02X1210424Y315805I-26J-790D01*
G03X1211014Y315510I616J495D01*
G01X1212514D01*
G03X1213104Y315805I-26J790D01*
G02X1213694Y316100I616J-495D01*
G01X1222710D01*
G02X1224400Y315400I0J-2390D01*
G01X1224900Y314900D01*
G03X1229402Y313035I4503J4503D01*
G01X1233845D01*
G02X1236515Y311929I1J-3774D01*
G01X1237222Y311222D01*
G03X1239568Y310250I2347J2347D01*
G01X1251820D01*
G02X1252173Y310104I0J-500D01*
G01X1253477Y308800D01*
X1253577D01*
G01X608069Y290355D02*
X610001Y292287D01*
G03Y293499I-606J606D01*
G01X609647Y293854D01*
G03X608086Y294500I-1560J-1561D01*
G01X608000D01*
G03X606293Y293793I0J-2414D01*
G01X605000Y292500D01*
G03X604500Y291293I1207J-1207D01*
G01Y289000D01*
G03X604854Y288147I1207J1D01*
G01X605500Y287500D01*
X606750Y286250D01*
G03X621597Y280100I14847J14847D01*
G01X624753D01*
G03X625343Y280395I-26J790D01*
G02X625933Y280690I616J-494D01*
G01X627433D01*
G02X628023Y280395I-26J-790D01*
G03X628613Y280100I616J494D01*
G01X630113D01*
G03X630703Y280395I-26J790D01*
G02X631293Y280690I616J-494D01*
G01X632793D01*
G02X633383Y280395I-26J-790D01*
G03X633973Y280100I616J494D01*
G01X635473D01*
G03X636063Y280395I-26J790D01*
G02X636653Y280690I616J-494D01*
G01X638153D01*
G02X638743Y280395I-26J-790D01*
G03X639333Y280100I616J494D01*
G01X645883D01*
G03X646473Y280395I-26J790D01*
G02X647063Y280690I616J-495D01*
G01X648563D01*
G02X649153Y280395I-26J-790D01*
G03X649743Y280100I616J495D01*
G01X651243D01*
G03X651833Y280395I-26J790D01*
G02X652423Y280690I616J-495D01*
G01X653923D01*
G02X654513Y280395I-26J-790D01*
G03X655103Y280100I616J495D01*
G01X656603D01*
G03X657193Y280395I-26J790D01*
G02X657783Y280690I616J-495D01*
G01X659283D01*
G02X659873Y280395I-26J-790D01*
G03X660463Y280100I616J495D01*
G01X716778D01*
G02X720400Y278600I0J-5122D01*
G01X722650Y276350D01*
G03X729531Y273500I6881J6881D01*
G01X894257D01*
G03X901500Y276500I0J10243D01*
G01X920900Y295900D01*
G02X929592Y299500I8692J-8692D01*
G01X1171403D01*
G03X1174300Y300700I0J4097D01*
G01X1174794Y301194D01*
G02X1183500Y304800I8706J-8706D01*
G01X1215569D01*
G02X1217500Y304000I0J-2731D01*
G01X1232750Y288750D01*
G03X1238665Y286300I5915J5915D01*
G01X1247977D01*
G03X1248283Y286312I11J3621D01*
G03X1248798Y286394I-310J3608D01*
G03X1250537Y287361I-822J3526D01*
G01X1250677Y287500D01*
G01X612009Y298230D02*
X610354Y296574D01*
G02X608001Y295600I-2352J2353D01*
G03X605515Y294571I-1J-3514D01*
G01X604222Y293278D01*
G03X603400Y291294I1985J-1985D01*
G01Y288999D01*
G03X604076Y287369I2307J1D01*
G01X604722Y286722D01*
X605972Y285472D01*
G03X621596Y279000I15625J15625D01*
G01X716778D01*
G02X719622Y277822I0J-4022D01*
G01X721872Y275572D01*
G03X729531Y272400I7658J7659D01*
G01X894257D01*
G03X902278Y275722I1J11343D01*
G01X921678Y295122D01*
G02X929592Y298400I7914J-7914D01*
G01X1171404D01*
G03X1175078Y299922I-1J5197D01*
G01X1175572Y300416D01*
G02X1183499Y303700I7928J-7928D01*
G01X1215568D01*
G02X1216722Y303222I0J-1631D01*
G01X1231972Y287972D01*
G03X1238665Y285200I6693J6693D01*
G01X1248377D01*
G02X1249402Y284776I1J-1449D01*
G01X1250677Y283500D01*
G01X600199Y315945D02*
X601697Y312947D01*
G02X601473Y312276I-448J-223D01*
G01X601472D01*
X601244Y312163D01*
X600892Y311987D01*
G03X600055Y310194I1499J-1792D01*
G01Y297762D01*
X600054Y297763D01*
G02X598777Y294678I-4363J-1D01*
G01X597703Y293605D01*
X596630Y292532D01*
G03X595955Y290900I1632J-1631D01*
G03X598045Y285854I7136J0D01*
G01X609914Y273985D01*
G03X617000Y271050I7086J7086D01*
G01X713700D01*
G02X717446Y269499I1J-5297D01*
G01X717472Y269472D01*
X719172Y267772D01*
G03X724899Y265400I5727J5728D01*
G01X897500D01*
G03X905960Y268904I0J11965D01*
G01X919028Y281972D01*
G02X928511Y285900I9483J-9483D01*
G01X1086934D01*
G02X1087900Y285500I0J-1366D01*
G03X1089107Y285000I1207J1207D01*
G01X1169367D01*
G03X1171285Y285785I1J2732D01*
G01X1171314Y285812D01*
G03X1172101Y287700I-1869J1887D01*
G01X1172100D01*
Y288448D01*
G02X1173777Y290125I1677J0D01*
G01X604134Y308070D02*
X602637Y311068D01*
G03X601966Y311292I-447J-223D01*
G01X601965D01*
X601962Y311291D01*
X601517Y311069D01*
G03X601155Y310195I874J-874D01*
G01Y297763D01*
G02X599555Y293900I-5463J0D01*
G01X597408Y291754D01*
G03X597055Y290900I854J-853D01*
G03X598823Y286632I6036J0D01*
G01X610692Y274763D01*
G03X617000Y272150I6308J6308D01*
G01X713700D01*
Y272151D01*
G02X718232Y270270I1J-6398D01*
G01X718264Y270236D01*
X719950Y268550D01*
G03X724899Y266500I4949J4950D01*
G01X897500D01*
G03X905182Y269682I0J10864D01*
G01X918250Y282750D01*
G02X928510Y287000I10261J-10261D01*
G01X938504D01*
G03X939094Y287295I-26J790D01*
G02X939684Y287590I616J-495D01*
G01X941184D01*
G02X941774Y287295I-26J-790D01*
G03X942364Y287000I616J495D01*
G01X943864D01*
G03X944454Y287295I-26J790D01*
G02X945044Y287590I616J-495D01*
G01X946544D01*
G02X947134Y287295I-26J-790D01*
G03X947724Y287000I616J495D01*
G01X949224D01*
G03X949814Y287295I-26J790D01*
G02X950404Y287590I616J-495D01*
G01X951904D01*
G02X952494Y287295I-26J-790D01*
G03X953084Y287000I616J495D01*
G01X973234D01*
G03X973824Y287295I-26J790D01*
G02X974414Y287590I616J-494D01*
G01X975914D01*
G02X976504Y287295I-26J-790D01*
G03X977094Y287000I616J494D01*
G01X978594D01*
G03X979184Y287295I-26J790D01*
G02X979774Y287590I616J-494D01*
G01X981274D01*
G02X981864Y287295I-26J-790D01*
G03X982454Y287000I616J494D01*
G01X983954D01*
G03X984544Y287295I-26J790D01*
G02X985134Y287590I616J-494D01*
G01X986634D01*
G02X987224Y287295I-26J-790D01*
G03X987814Y287000I616J494D01*
G01X1005787D01*
G03X1006377Y287295I-26J790D01*
G02X1006967Y287590I616J-494D01*
G01X1008467D01*
G02X1009057Y287295I-26J-790D01*
G03X1009647Y287000I616J494D01*
G01X1011147D01*
G03X1011737Y287295I-26J790D01*
G02X1012327Y287590I616J-494D01*
G01X1013827D01*
G02X1014417Y287295I-26J-790D01*
G03X1015007Y287000I616J494D01*
G01X1016507D01*
G03X1017097Y287295I-26J790D01*
G02X1017687Y287590I616J-494D01*
G01X1019187D01*
G02X1019777Y287295I-26J-790D01*
G03X1020367Y287000I616J494D01*
G01X1086933D01*
G02X1088678Y286278I2J-2466D01*
G03X1089108Y286100I429J429D01*
G01X1169368D01*
G03X1170522Y286578I0J1632D01*
G01X1170545Y286600D01*
G03X1171000Y287700I-1100J1099D01*
G01Y288400D01*
G03X1170645Y289257I-1212J0D01*
G01X1169777Y290125D01*
G01X722244Y298230D02*
G03X721557Y296571I1659J-1659D01*
G01Y294754D01*
G03X722060Y293540I1717J0D01*
G02X722700Y291400I-3261J-2141D01*
G01Y288405D01*
G03X723668Y286068I3305J0D01*
G01X728035Y281701D01*
G03X731900Y280100I3865J3865D01*
G01X889928D01*
G03X897050Y283050I0J10072D01*
G01X918484Y304484D01*
G02X924800Y307100I6316J-6317D01*
G01X1162500D01*
G03X1164932Y308108I-1J3440D01*
G01X1165000Y308175D01*
G01X718309Y290355D02*
X718308Y291868D01*
G02X720408Y293110I1418J-1D01*
G02X720611Y292975I-681J-1243D01*
G02X720729Y292871I-877J-1114D01*
G01X721176Y292425D01*
G02X721600Y291400I-1025J-1024D01*
G01Y288405D01*
G03X722890Y285290I4405J0D01*
G01X727257Y280923D01*
G03X731900Y279000I4643J4644D01*
G01X889928D01*
G03X897828Y282272I0J11172D01*
G01X919262Y303706D01*
G02X924800Y306000I5538J-5538D01*
G01X1163100D01*
G02X1163894Y305671I0J-1123D01*
G01X1165000Y304565D01*
G01X730119Y308070D02*
X729000Y309189D01*
G02Y311500I1156J1156D01*
G02X729966Y311900I966J-966D01*
G01X730742D01*
G02X731285Y311675I0J-768D01*
G01X732980Y309980D01*
G02X733580Y308531I-1449J-1449D01*
G01Y297435D01*
G03X734475Y295275I3056J1D01*
G01X736725Y293025D01*
G02X737200Y291878I-1146J-1146D01*
G01Y289900D01*
G03X738041Y287869I2873J0D01*
G01X739155Y286755D01*
G03X741943Y285600I2789J2789D01*
G01X886610D01*
G03X890563Y287237I1J5590D01*
G01X914813Y311487D01*
G02X920638Y313900I5825J-5825D01*
G01X1154000D01*
G02X1155698Y313196I-1J-2402D01*
G01X1156100Y312795D01*
G01X726179Y315945D02*
X728254Y313870D01*
X728700Y313425D01*
G03X729570Y313064I871J870D01*
G01X730700D01*
G02X731983Y312532I-1J-1815D01*
G01X732058Y312458D01*
X733758Y310758D01*
G02X734680Y308531I-2227J-2226D01*
G01Y297436D01*
G03X735253Y296053I1956J0D01*
G01X737503Y293803D01*
G02X738300Y291879I-1924J-1924D01*
G01Y289900D01*
G03X738819Y288647I1772J0D01*
G01X739933Y287533D01*
G03X741944Y286700I2011J2011D01*
G01X886610D01*
G03X889785Y288015I0J4490D01*
G01X914035Y312265D01*
G02X920637Y315000I6603J-6603D01*
G01X1154000D01*
G03X1155187Y315491I1J1678D01*
G01X1156100Y316405D01*
G01X1023500Y727000D02*
X1020000Y730500D01*
Y735182D01*
X999982Y755200D01*
X914178D01*
X829000Y840378D01*
Y864031D01*
X827031Y866000D01*
X822500D01*
X820000Y868500D01*
X819000D01*
G01X1001100Y776500D02*
X999000Y774400D01*
Y769908D01*
X986498Y757406D01*
X914096D01*
X830808Y840694D01*
Y864345D01*
X826593Y868560D01*
X824560D01*
G01X863820Y363880D02*
X865770Y361930D01*
X870123D01*
X870303Y362110D01*
X899890D01*
X902300Y359700D01*
X1043800D01*
X1048430Y355070D01*
X1162676D01*
X1163356Y355750D01*
X1170261D01*
X1179950Y365439D01*
Y530857D01*
X1199319Y550226D01*
X1219543D01*
X1255817Y586500D01*
X1264258D01*
X1284825Y607067D01*
Y621500D01*
G01X868820Y363880D02*
X869550Y364610D01*
X902390D01*
X905000Y362000D01*
X1045000D01*
X1049630Y357370D01*
X1161723D01*
X1162403Y358050D01*
X1169308D01*
X1177075Y365817D01*
Y380167D01*
X1174550Y382692D01*
Y401292D01*
X1176550Y403292D01*
Y530710D01*
X1198366Y552526D01*
X1213206D01*
X1279340Y618660D01*
G01X963500Y256000D02*
X985000Y234500D01*
X1070000D01*
X1090000Y254500D01*
X1125000D01*
X1126000Y253500D01*
X1150500D01*
X1153000Y256000D01*
X1170000D01*
X1174500Y251500D01*
X1181427D01*
G01X962000D02*
X981000Y232500D01*
X1071000D01*
X1090500Y252000D01*
X1114500D01*
X1115000Y252500D01*
X1124000D01*
X1125000Y251500D01*
X1151500D01*
X1154000Y254000D01*
X1169000D01*
X1173500Y249500D01*
X1187000D01*
X1188000Y248500D01*
G01X965500Y260500D02*
X972000Y254000D01*
X1016500D01*
X1034000Y236500D01*
X1069000D01*
X1089000Y256500D01*
X1126000D01*
X1126482Y256018D01*
X1150018D01*
X1152000Y258000D01*
X1159500D01*
X1161500Y260000D01*
X1163500D01*
X1165500Y258000D01*
X1171000D01*
X1172982Y256018D01*
X1180195D01*
X1180677Y256500D01*
G01X959500Y351688D02*
X1045730D01*
X1047868Y349550D01*
X1184808D01*
X1186558Y351300D01*
X1225700D01*
X1236000Y341000D01*
X1240000D01*
X1248000Y333000D01*
X1260500D01*
X1266077Y327423D01*
Y268406D01*
X1258608Y260937D01*
Y248569D01*
X1261677Y245500D01*
G01X964000Y354000D02*
X1046247D01*
X1047477Y352770D01*
X1163629D01*
X1164309Y353450D01*
X1171214D01*
X1172164Y354400D01*
X1215771D01*
X1216721Y353450D01*
X1227550D01*
X1238000Y343000D01*
X1241000D01*
X1249000Y335000D01*
X1261329D01*
X1268500Y327829D01*
Y268000D01*
X1260608Y260108D01*
Y254063D01*
X1263627Y251044D01*
Y243450D01*
X1261677Y241500D01*
G01X992690Y466750D02*
Y469550D01*
X975050Y487190D01*
Y553808D01*
X976750Y555508D01*
Y692997D01*
X970750Y698997D01*
Y703000D01*
G01X996910Y466560D02*
Y469450D01*
X979950Y486410D01*
Y693050D01*
X975000Y698000D01*
Y701000D01*
G01X1002500Y653000D02*
Y627000D01*
X992500Y617000D01*
Y534500D01*
X989700Y531700D01*
Y505042D01*
X991742Y503000D01*
X1051000D01*
X1092500Y461500D01*
G01X992000Y505500D02*
X994758D01*
X999500Y510242D01*
Y528000D01*
X1000500Y529000D01*
Y613500D01*
X1019000Y632000D01*
Y672000D01*
X1026500Y679500D01*
Y796000D01*
X1035000Y804500D01*
G01X1001100Y776500D02*
X1042600Y818000D01*
X1051622D01*
X1070000Y836378D01*
Y946058D01*
X1084567Y960625D01*
X1162000D01*
G01X1035000Y800000D02*
X1028000Y793000D01*
Y678500D01*
X1020500Y671000D01*
Y631000D01*
X1006550Y617050D01*
Y524450D01*
X1007500Y523500D01*
Y507000D01*
G01X1068300Y488700D02*
Y492425D01*
X1033050Y527675D01*
Y637550D01*
X1035800Y640300D01*
Y715300D01*
X1039500Y719000D01*
Y744312D01*
X1040208Y745020D01*
G01X1037000Y734000D02*
X1032950Y729950D01*
Y664450D01*
X1025500Y657000D01*
G01X1038500Y706500D02*
Y662158D01*
X1037500Y661158D01*
Y638500D01*
X1036050Y637050D01*
Y600450D01*
X1052500Y584000D01*
Y522500D01*
X1130000Y445000D01*
Y361500D01*
G01X1038000Y604000D02*
X1042450Y608450D01*
Y648500D01*
G01X1045500Y639500D02*
Y614500D01*
X1056000Y604000D01*
G01X1053500Y620500D02*
X1048000Y626000D01*
Y651500D01*
X1046850Y652650D01*
Y767700D01*
X1052500Y773350D01*
G01X1142640Y359860D02*
X1135000Y367500D01*
Y443000D01*
X1055000Y523000D01*
Y600000D01*
X1058000Y603000D01*
Y619000D01*
X1050092Y626908D01*
Y655052D01*
G01X1038000Y635000D02*
X1040450Y637450D01*
Y649329D01*
X1044350Y653229D01*
Y685308D01*
X1044000Y685658D01*
Y763940D01*
G01X1058000Y599500D02*
Y600000D01*
X1060000Y602000D01*
Y620000D01*
X1054000Y626000D01*
Y654800D01*
X1048850Y659950D01*
Y711684D01*
X1052300Y715134D01*
Y733942D01*
X1052050Y734192D01*
Y735808D01*
X1055000Y738758D01*
Y746592D01*
X1054400Y747192D01*
Y748808D01*
X1054650Y749058D01*
Y814555D01*
X1055000Y814905D01*
Y815500D01*
X1077000Y837500D01*
Y943075D01*
G01X1059000Y558190D02*
Y564500D01*
X1057500Y566000D01*
Y595500D01*
X1062000Y600000D01*
Y620405D01*
X1056000Y626405D01*
Y656000D01*
X1050550Y661450D01*
Y704714D01*
X1052836Y707000D01*
X1053258D01*
X1054598Y708340D01*
Y713902D01*
X1054000Y714500D01*
Y735000D01*
G01X1058500Y660900D02*
X1060000Y659400D01*
Y629500D01*
X1067500Y622000D01*
Y599500D01*
X1061500Y593500D01*
Y568000D01*
X1063500Y566000D01*
Y521000D01*
X1142500Y442000D01*
Y368000D01*
X1150640Y359860D01*
G01X1054900Y660900D02*
X1058000Y657800D01*
Y628500D01*
X1065500Y621000D01*
Y600500D01*
X1059500Y594500D01*
Y567000D01*
X1061500Y565000D01*
Y520000D01*
X1138900Y442600D01*
Y368100D01*
X1146640Y360360D01*
Y359860D01*
G01X1058350Y681450D02*
Y666350D01*
X1066810Y657890D01*
Y653122D01*
X1066050Y652362D01*
Y648950D01*
X1075500Y639500D01*
Y631500D01*
X1072500Y628500D01*
Y599000D01*
X1065500Y592000D01*
Y586000D01*
X1067500Y584000D01*
Y522671D01*
X1098171Y492000D01*
X1100683D01*
X1102533Y490150D01*
X1105349D01*
X1126000Y469500D01*
Y469000D01*
X1144500Y450500D01*
Y369000D01*
X1153830Y359670D01*
X1160770D01*
X1161530Y360430D01*
G01X1124327Y465391D02*
X1122109D01*
X1065796Y521704D01*
Y583204D01*
X1063500Y585500D01*
Y592500D01*
X1069500Y598500D01*
Y624500D01*
X1064055Y629945D01*
X1062940D01*
G01X1157480Y361620D02*
X1157100Y362000D01*
X1154411D01*
X1146500Y369911D01*
Y452000D01*
X1104500Y494000D01*
X1099000D01*
X1069500Y523500D01*
Y585000D01*
X1067500Y587000D01*
Y591000D01*
X1078000Y601500D01*
Y639967D01*
X1068050Y649917D01*
Y651533D01*
X1068810Y652293D01*
Y676690D01*
X1068500Y677000D01*
G01X1071500Y589000D02*
X1081500Y599000D01*
Y646727D01*
X1079500Y648727D01*
Y652730D01*
X1077180Y655050D01*
Y674456D01*
X1075950Y675686D01*
Y677808D01*
X1072258Y681500D01*
X1070170D01*
X1063340Y688330D01*
Y741010D01*
X1056350Y748000D01*
G01X1066000Y717000D02*
Y689500D01*
X1068500Y687000D01*
G01X1160058Y364558D02*
X1160000D01*
X1159942Y364500D01*
X1155500D01*
X1148500Y371500D01*
Y453000D01*
X1091000Y510500D01*
X1085500D01*
X1071500Y524500D01*
Y586000D01*
X1069500Y588000D01*
Y590000D01*
X1080000Y600500D01*
Y641860D01*
X1071950Y649910D01*
Y651540D01*
X1070810Y652680D01*
Y678640D01*
X1059800Y689650D01*
Y719740D01*
G01X1083700Y835725D02*
X1078225D01*
X1056350Y813850D01*
Y748000D01*
G01X1083200Y956500D02*
Y838983D01*
X1085650Y836533D01*
Y834917D01*
X1081000Y830267D01*
Y798000D01*
X1063000Y780000D01*
G01X1175125Y370000D02*
X1174775D01*
X1161621Y383154D01*
Y449800D01*
X1118121Y493300D01*
Y516042D01*
X1109542Y524621D01*
X1098021D01*
X1079050Y543592D01*
Y586577D01*
X1096450Y603977D01*
Y718060D01*
X1090257Y724253D01*
G01X1081000Y548000D02*
Y551000D01*
X1080850Y551150D01*
Y569704D01*
X1122180Y611034D01*
X1139036D01*
X1143036Y615034D01*
X1153569D01*
X1185965Y647430D01*
Y676573D01*
G01X1081000Y544400D02*
X1082950Y546350D01*
Y551503D01*
X1082350Y552103D01*
Y569082D01*
X1122535Y609267D01*
X1139768D01*
X1143768Y613267D01*
X1154767D01*
X1218500Y677000D01*
X1223500D01*
X1228500Y682000D01*
X1235000D01*
G01X1087600Y727029D02*
Y721747D01*
X1092950Y716397D01*
Y659650D01*
X1088650Y655350D01*
Y653067D01*
X1085400Y649817D01*
Y595400D01*
X1077350Y587350D01*
Y542887D01*
X1097737Y522500D01*
X1109258D01*
X1116000Y515758D01*
Y493016D01*
X1159500Y449516D01*
Y381000D01*
X1174500Y366000D01*
G01X1085000Y661000D02*
Y652500D01*
X1083500Y651000D01*
Y598242D01*
X1075650Y590392D01*
Y542182D01*
X1097332Y520500D01*
X1108500D01*
X1111500Y517500D01*
G01X1201250Y627000D02*
X1199000D01*
X1196050Y629950D01*
X1173950D01*
X1155500Y611500D01*
X1144500D01*
X1140500Y607500D01*
X1123173D01*
X1084050Y568377D01*
Y553950D01*
X1084650Y553350D01*
Y545150D01*
X1084599Y545099D01*
Y544520D01*
G01X1136075Y559075D02*
X1100575D01*
G01X1132000Y562000D02*
X1098000D01*
G01X1091425Y551425D02*
X1095000Y555000D01*
Y574800D01*
X1120200Y600000D01*
X1149000D01*
X1164450Y615450D01*
X1183292D01*
X1185192Y613550D01*
X1270303D01*
X1280203Y623450D01*
X1289450D01*
X1294000Y628000D01*
G01X1086000Y556000D02*
X1091500Y561500D01*
Y573422D01*
X1123578Y605500D01*
X1152258D01*
X1168758Y622000D01*
X1201000D01*
X1204500Y625500D01*
X1239000D01*
X1247050Y633550D01*
X1258308D01*
X1260258Y635500D01*
X1290500D01*
G01X1094853Y726853D02*
X1092727Y728979D01*
X1086792D01*
X1085650Y727837D01*
Y717150D01*
X1091000Y711800D01*
Y692519D01*
G01X1107500Y580000D02*
X1116900Y570600D01*
X1125600D01*
G01X1385135Y581195D02*
X1384000Y582330D01*
Y590944D01*
X1389600Y596544D01*
Y678456D01*
X1371256Y696800D01*
X1324700D01*
X1313500Y708000D01*
X1266500D01*
X1256500Y718000D01*
X1246563D01*
X1226000Y738563D01*
Y752555D01*
X1194586Y783969D01*
Y783970D01*
X1193000Y788200D01*
Y793702D01*
G03X1190628Y799428I-8099J-1D01*
G01X1177828Y812228D01*
G03X1170895Y815100I-6934J-6934D01*
G01X1125615D01*
G03X1120372Y812928I1J-7416D01*
G01X1114422Y806978D01*
G03X1113000Y803544I3434J-3433D01*
G01Y774700D01*
G03X1115302Y769142I7861J0D01*
G01X1118472Y765972D01*
G02X1119900Y762525I-3447J-3447D01*
G01Y735778D01*
G03X1120772Y733672I2978J0D01*
G01X1121274Y733170D01*
G02X1121800Y731900I-1270J-1270D01*
G02X1121022Y730022I-2656J0D01*
G01X1120500Y729500D01*
G01X1124000Y729000D02*
G02X1122900Y731656I2656J2656D01*
G01Y731900D01*
G03X1122052Y733948I-2897J0D01*
G01X1121550Y734450D01*
G02X1121000Y735778I1328J1328D01*
G01Y762526D01*
G03X1119250Y766750I-5975J-1D01*
G01X1116080Y769920D01*
G02X1114100Y774700I4780J4780D01*
G01Y803544D01*
G02X1115200Y806200I3756J0D01*
G01X1121150Y812150D01*
G02X1125616Y814000I4466J-4466D01*
G01X1170894D01*
G02X1177050Y811450I0J-8706D01*
G01X1189850Y798650D01*
G02X1191900Y793701I-4949J-4949D01*
G01Y787998D01*
X1193486Y783770D01*
Y783513D01*
X1224900Y752099D01*
Y738107D01*
X1246107Y716900D01*
X1256044D01*
X1266044Y706900D01*
X1313044D01*
X1324244Y695700D01*
X1327553D01*
X1328143Y695110D01*
X1329643D01*
X1330233Y695700D01*
X1331733D01*
X1332323Y695110D01*
X1333823D01*
X1334413Y695700D01*
X1335913D01*
X1336503Y695110D01*
X1338003D01*
X1338593Y695700D01*
X1341734D01*
X1342324Y695110D01*
X1343824D01*
X1344414Y695700D01*
X1345914D01*
X1346504Y695110D01*
X1348004D01*
X1348594Y695700D01*
X1350094D01*
X1350684Y695110D01*
X1352184D01*
X1352774Y695700D01*
X1357911D01*
X1358501Y695110D01*
X1360001D01*
X1360591Y695700D01*
X1362091D01*
X1362681Y695110D01*
X1364181D01*
X1364771Y695700D01*
X1370800D01*
X1372476Y694024D01*
Y693190D01*
X1373536Y692129D01*
X1374371D01*
X1375431Y691069D01*
Y690234D01*
X1376492Y689174D01*
X1377326D01*
X1378387Y688113D01*
Y687279D01*
X1379448Y686218D01*
X1380282D01*
X1382413Y684087D01*
Y683253D01*
X1383473Y682192D01*
X1384308D01*
X1388500Y678000D01*
Y597000D01*
X1382900Y591400D01*
Y582680D01*
X1381415Y581195D01*
G01X1145270Y792670D02*
X1143890Y791290D01*
Y788842D01*
X1141998Y786950D01*
X1140975D01*
X1139825Y785800D01*
X1137419D01*
X1134486Y782867D01*
Y781417D01*
X1135995Y779908D01*
Y746882D01*
X1135180Y746067D01*
Y731980D01*
X1145240Y721920D01*
Y718110D01*
X1147550Y715800D01*
X1149810D01*
X1151307Y714306D01*
G01X1149743Y721757D02*
X1149346D01*
X1148819Y722284D01*
X1147451D01*
X1147427Y722260D01*
X1146315D01*
X1138880Y729695D01*
Y746067D01*
X1137695Y747252D01*
Y775731D01*
X1137211Y776215D01*
Y777665D01*
X1138900Y779354D01*
Y783221D01*
X1140792Y785113D01*
X1141700D01*
G01X1154190Y720635D02*
X1145650Y729175D01*
Y730625D01*
X1142280Y733995D01*
Y747477D01*
X1141095Y748662D01*
Y765695D01*
X1141700Y766300D01*
X1146200D01*
G01X1151590Y792660D02*
Y792561D01*
X1147490Y788461D01*
Y782290D01*
X1139395Y774195D01*
Y747957D01*
X1140580Y746772D01*
Y736295D01*
X1139880Y735595D01*
Y733120D01*
X1153240Y719760D01*
Y719590D01*
X1154430Y718399D01*
Y717481D01*
G01X1150734Y736950D02*
X1144750D01*
X1143980Y737720D01*
Y748182D01*
X1143000Y749162D01*
Y763575D01*
X1143975Y764550D01*
X1146925D01*
X1148120Y765745D01*
Y770035D01*
X1145945Y772210D01*
Y775150D01*
X1147015Y776220D01*
Y780218D01*
X1148100Y781303D01*
X1153219D01*
G01X1149470Y734451D02*
X1150569D01*
X1152384Y736266D01*
Y737634D01*
X1151418Y738600D01*
X1146300D01*
X1145680Y739220D01*
Y750910D01*
X1144700Y751890D01*
Y752910D01*
X1145680Y753890D01*
Y754910D01*
X1144700Y755890D01*
Y756910D01*
X1145680Y757890D01*
Y758910D01*
X1144700Y759890D01*
Y760910D01*
X1149120Y765330D01*
Y768998D01*
X1149620Y769498D01*
X1151500D01*
X1152000Y769998D01*
Y770998D01*
X1151500Y771498D01*
X1149620D01*
X1148300Y772818D01*
Y775700D01*
X1149524Y776924D01*
X1151564D01*
G01X1155630Y724370D02*
X1154450Y725550D01*
Y734250D01*
X1154084Y734616D01*
Y738339D01*
X1152123Y740300D01*
X1148400D01*
X1147380Y741320D01*
Y761185D01*
X1150120Y763925D01*
Y766520D01*
X1153150Y769550D01*
Y771752D01*
X1153600Y772202D01*
Y778108D01*
X1154969Y779477D01*
Y782721D01*
X1153500Y784190D01*
G01X1185500Y548075D02*
X1168000Y530575D01*
Y416758D01*
X1168450Y416308D01*
Y401450D01*
X1164000Y397000D01*
G01X1166500Y415500D02*
Y536000D01*
X1161000Y541500D01*
G01X1163905Y711206D02*
X1162142D01*
X1161248Y712100D01*
Y713148D01*
X1161748Y713648D01*
X1162400D01*
X1162900Y714148D01*
Y715148D01*
X1162400Y715648D01*
X1161748D01*
X1161248Y716148D01*
Y721711D01*
X1164450Y724913D01*
Y732250D01*
X1166050Y733850D01*
Y748296D01*
X1164597Y749749D01*
X1162651D01*
X1162283Y750117D01*
Y754408D01*
X1161400Y755291D01*
Y759221D01*
X1161420Y759241D01*
Y765520D01*
X1162340Y766440D01*
X1163590D01*
X1164658Y767508D01*
X1167002D01*
G01X1161022Y785693D02*
X1160943Y785614D01*
Y776947D01*
X1162070Y775820D01*
Y773231D01*
X1164200Y771100D01*
Y768465D01*
X1163175Y767440D01*
X1160260D01*
X1159720Y766900D01*
Y759946D01*
X1159700Y759926D01*
Y759200D01*
X1158383Y757883D01*
Y747690D01*
X1164150Y741923D01*
Y735895D01*
X1163450Y735195D01*
Y725328D01*
X1160248Y722126D01*
Y714664D01*
X1157636Y712052D01*
Y711200D01*
G01X1169698Y719513D02*
Y721140D01*
X1181100Y732542D01*
Y733185D01*
X1181800Y733885D01*
Y735102D01*
X1182500Y735802D01*
Y775798D01*
X1169048Y789250D01*
X1164338D01*
X1163932Y788844D01*
X1161545D01*
G01X1158092Y787715D02*
Y785327D01*
X1158272Y785147D01*
Y776788D01*
X1159621Y775439D01*
Y772246D01*
X1158825Y771450D01*
X1157375D01*
X1156350Y770425D01*
Y765096D01*
X1156320Y765066D01*
Y761356D01*
X1154600Y759636D01*
Y746663D01*
X1160750Y740513D01*
Y735984D01*
X1159550Y734784D01*
Y731806D01*
X1157643Y729899D01*
Y728899D01*
X1158143Y728399D01*
X1160200D01*
X1160700Y727899D01*
Y726899D01*
X1160200Y726399D01*
X1158143D01*
X1157643Y725899D01*
Y720642D01*
G01X1159550Y723090D02*
X1162450Y725990D01*
Y741218D01*
X1156300Y747368D01*
Y758931D01*
X1158020Y760651D01*
Y767145D01*
X1160900Y770025D01*
Y775575D01*
X1159272Y777203D01*
Y786420D01*
X1159842Y786990D01*
Y788440D01*
X1158300Y789982D01*
Y792935D01*
X1155445Y795790D01*
X1154700D01*
G01X1170911Y784912D02*
X1180800Y775023D01*
Y734300D01*
X1180100Y733600D01*
Y732957D01*
X1168698Y721555D01*
Y719928D01*
X1167732Y718962D01*
X1167547D01*
X1167049Y718464D01*
Y717501D01*
G01X1167048Y720612D02*
Y721320D01*
X1179100Y733372D01*
Y774186D01*
X1171536Y781750D01*
X1171086D01*
X1170718Y782118D01*
G01X1165063Y787500D02*
X1165355Y787208D01*
Y783569D01*
X1169076Y779848D01*
Y776924D01*
X1174000Y772000D01*
Y736344D01*
X1173150Y735494D01*
Y731242D01*
X1167608Y725700D01*
X1166652D01*
X1162248Y721296D01*
Y719112D01*
X1163898Y717462D01*
G01Y720612D02*
X1165806Y722520D01*
X1165843D01*
X1177400Y734077D01*
Y773481D01*
X1172858Y778023D01*
Y778093D01*
X1171833Y779118D01*
X1171243D01*
X1167410Y782951D01*
Y785530D01*
G01X1264500Y260000D02*
X1270500Y266000D01*
Y328658D01*
X1262158Y337000D01*
X1250000D01*
X1242000Y345000D01*
X1239913D01*
X1229463Y355450D01*
X1217550D01*
X1184450Y388550D01*
Y407808D01*
X1183500Y408758D01*
Y531154D01*
X1199846Y547500D01*
X1200075D01*
X1200500Y547925D01*
G01X1196000Y605800D02*
X1176775D01*
X1169075Y613500D01*
G01X1377996Y610847D02*
X1376749Y609600D01*
X1375456D01*
X1373600Y611456D01*
Y628544D01*
X1384100Y639044D01*
Y674456D01*
X1368956Y689600D01*
X1321400D01*
X1309500Y701500D01*
X1269500D01*
X1264500Y696500D01*
X1258556D01*
X1252056Y703000D01*
X1222510D01*
X1215510Y696000D01*
X1190180D01*
X1186091Y691911D01*
X1182478D01*
X1179678Y689111D01*
G01X1377996Y607382D02*
X1376878Y608500D01*
X1375000D01*
X1372500Y611000D01*
Y629000D01*
X1383000Y639500D01*
Y674000D01*
X1368500Y688500D01*
X1362479D01*
X1361889Y687910D01*
X1360389D01*
X1359799Y688500D01*
X1358299D01*
X1357709Y687910D01*
X1356209D01*
X1355619Y688500D01*
X1354119D01*
X1353529Y687910D01*
X1352029D01*
X1351439Y688500D01*
X1337062D01*
X1336472Y687910D01*
X1334972D01*
X1334382Y688500D01*
X1332882D01*
X1332292Y687910D01*
X1330792D01*
X1330202Y688500D01*
X1328702D01*
X1328112Y687910D01*
X1326612D01*
X1326022Y688500D01*
X1320944D01*
X1309044Y700400D01*
X1269956D01*
X1264956Y695400D01*
X1258100D01*
X1251600Y701900D01*
X1222966D01*
X1215966Y694900D01*
X1190636D01*
X1186547Y690811D01*
X1183623D01*
X1182817Y690005D01*
Y689155D01*
G01X1170199Y717501D02*
Y718599D01*
X1170698Y719098D01*
Y720725D01*
X1185000Y735027D01*
Y746000D01*
X1188107Y749107D01*
Y753348D01*
X1194000Y759241D01*
Y764500D01*
G01X1171500Y733725D02*
X1171450Y733775D01*
Y735183D01*
X1172300Y736033D01*
Y771962D01*
X1167326Y776936D01*
G01X1175000Y734870D02*
X1175700Y735570D01*
Y772776D01*
X1171108Y777368D01*
G01X1191000Y528000D02*
Y504000D01*
X1199000Y496000D01*
Y428258D01*
X1199450Y427808D01*
Y382634D01*
X1222634Y359450D01*
X1231121D01*
X1235821Y354750D01*
X1239808D01*
X1253558Y341000D01*
X1264329D01*
X1274500Y330829D01*
Y243823D01*
X1264177Y233500D01*
G01X1189000Y533825D02*
X1185500Y530325D01*
Y415758D01*
X1189450Y411808D01*
Y386379D01*
X1218379Y357450D01*
X1230292D01*
X1240742Y347000D01*
X1243000D01*
X1251000Y339000D01*
X1263500D01*
X1272500Y330000D01*
Y264884D01*
X1262558Y254942D01*
G01X1267677Y232500D02*
X1276500Y241323D01*
Y331658D01*
X1265158Y343000D01*
X1256000D01*
X1242250Y356750D01*
X1236650D01*
X1231950Y361450D01*
X1223463D01*
X1201450Y383463D01*
Y428637D01*
X1201000Y429087D01*
Y524500D01*
X1194564Y530936D01*
G01X1299000Y641500D02*
Y637989D01*
X1290561Y629550D01*
X1249061D01*
X1238783Y619272D01*
X1184956D01*
G01X1377896Y29526D02*
Y36515D01*
X1365411Y49000D01*
X1360476D01*
X1318500Y90976D01*
Y127000D01*
X1314867Y130633D01*
Y317304D01*
X1308000Y324171D01*
Y351500D01*
X1262500Y397000D01*
Y423500D01*
X1253000Y433000D01*
Y441500D01*
X1237250Y457250D01*
Y483421D01*
X1257500Y503671D01*
Y512687D01*
X1292063Y547250D01*
X1294140D01*
X1315950Y569060D01*
Y657295D01*
X1299734Y673511D01*
X1281489D01*
X1278050Y676950D01*
X1265691D01*
X1265412Y676671D01*
X1251712D01*
X1244383Y684000D01*
X1227000D01*
X1223053Y680053D01*
X1203466D01*
X1199551Y683968D01*
G01X1195937Y683849D02*
X1198887Y686799D01*
X1219755D01*
X1222956Y690000D01*
X1251050D01*
X1254150Y686900D01*
X1303542D01*
X1310892Y679550D01*
X1311492D01*
X1322000Y669042D01*
Y630287D01*
X1325067Y627220D01*
Y625604D01*
X1322000Y622537D01*
Y564355D01*
X1289950Y532305D01*
Y450500D01*
X1285500Y446050D01*
Y435500D01*
X1278050Y428050D01*
Y390450D01*
X1314000Y354500D01*
Y333000D01*
X1325950Y321050D01*
Y92037D01*
X1362987Y55000D01*
X1367898D01*
X1389016Y33882D01*
Y24906D01*
X1385766Y21656D01*
G01X1380925Y602035D02*
X1379890Y601000D01*
X1374056D01*
X1368600Y606456D01*
Y631544D01*
X1378100Y641044D01*
Y656209D01*
X1378690Y656799D01*
Y658299D01*
X1378100Y658889D01*
Y660389D01*
X1378690Y660979D01*
Y662479D01*
X1378100Y663069D01*
Y664569D01*
X1378690Y665159D01*
Y666659D01*
X1378100Y667249D01*
Y670956D01*
X1375434Y673622D01*
Y674457D01*
X1374373Y675517D01*
X1373539D01*
X1365056Y684000D01*
X1350471D01*
X1349881Y684590D01*
X1348381D01*
X1347791Y684000D01*
X1346291D01*
X1345701Y684590D01*
X1344201D01*
X1343611Y684000D01*
X1342111D01*
X1341521Y684590D01*
X1340021D01*
X1339431Y684000D01*
X1320000D01*
X1308000Y696000D01*
X1286000D01*
X1281500Y691500D01*
X1256056D01*
X1251005Y696551D01*
X1245911D01*
X1245321Y697141D01*
X1243821D01*
X1243231Y696551D01*
X1241731D01*
X1241141Y697141D01*
X1239641D01*
X1239051Y696551D01*
X1237551D01*
X1236961Y697141D01*
X1235461D01*
X1234871Y696551D01*
X1231697D01*
X1231107Y697141D01*
X1229607D01*
X1229017Y696551D01*
X1223001D01*
X1217850Y691400D01*
X1193844D01*
X1191911Y689467D01*
Y687056D01*
X1189938Y685083D01*
X1189890Y684053D01*
G01X1380925Y598315D02*
Y598475D01*
X1379500Y599900D01*
X1373600D01*
X1367500Y606000D01*
Y632000D01*
X1377000Y641500D01*
Y670500D01*
X1364600Y682900D01*
X1319544D01*
X1307544Y694900D01*
X1286456D01*
X1281956Y690400D01*
X1255600D01*
X1250549Y695451D01*
X1223457D01*
X1218306Y690300D01*
X1217397D01*
X1217396Y690299D01*
X1216945D01*
X1216944Y690300D01*
X1194300D01*
X1193011Y689011D01*
Y685486D01*
X1192937Y683911D01*
G01X1233000Y554502D02*
X1217748Y539250D01*
X1216068D01*
X1205050Y528232D01*
Y430695D01*
X1205450Y430295D01*
Y392963D01*
X1232913Y365500D01*
X1233558D01*
X1237058Y362000D01*
X1251816D01*
X1280500Y333316D01*
Y238000D01*
X1276500Y234000D01*
G01X1346396Y29526D02*
Y31104D01*
X1328500Y49000D01*
X1314317D01*
X1280500Y82817D01*
Y84000D01*
X1274550Y89950D01*
Y234879D01*
X1278500Y238829D01*
Y332487D01*
X1251987Y359000D01*
X1237229D01*
X1232729Y363500D01*
X1224242D01*
X1203450Y384292D01*
Y429466D01*
X1203000Y429916D01*
Y528600D01*
X1201500Y530100D01*
Y535000D01*
G01X1221500Y539500D02*
Y538000D01*
X1207500Y524000D01*
Y443000D01*
X1210950Y439550D01*
Y437450D01*
X1207500Y434000D01*
Y395242D01*
X1238742Y364000D01*
X1253800D01*
X1264800Y353000D01*
X1273855D01*
X1282500Y344355D01*
Y83646D01*
X1315146Y51000D01*
X1329329D01*
X1347553Y32776D01*
X1347743D01*
X1349646Y30873D01*
Y24906D01*
X1346396Y21656D01*
G01X1210000Y507500D02*
X1209500Y507000D01*
Y444000D01*
X1213750Y439750D01*
Y437860D01*
X1214500Y437110D01*
Y435000D01*
X1209500Y430000D01*
Y404500D01*
G01X1354271Y29526D02*
Y30491D01*
X1348986Y35776D01*
X1348796D01*
X1330572Y54000D01*
X1316389D01*
X1285500Y84889D01*
Y345598D01*
X1275098Y356000D01*
X1266043D01*
X1243000Y379043D01*
Y410000D01*
X1221500Y431500D01*
Y439500D01*
X1215050Y445950D01*
Y500550D01*
X1229500Y515000D01*
Y533000D01*
G01X1208500Y623000D02*
X1239258D01*
X1248108Y631850D01*
X1289608D01*
X1296000Y638242D01*
Y638500D01*
G01X1241000Y631500D02*
X1238450Y628950D01*
X1203200D01*
X1201250Y627000D01*
G01X1377896Y21656D02*
X1381146Y24906D01*
Y36094D01*
X1366240Y51000D01*
X1361327D01*
X1320500Y91827D01*
Y128500D01*
X1316867Y132133D01*
Y318133D01*
X1310000Y325000D01*
Y352500D01*
X1266950Y395550D01*
Y427308D01*
X1255000Y439258D01*
Y443000D01*
X1239250Y458750D01*
Y482592D01*
X1259500Y502842D01*
Y511858D01*
X1292892Y545250D01*
X1294969D01*
X1317950Y568231D01*
Y658124D01*
X1295174Y680900D01*
X1252717D01*
X1247617Y686000D01*
X1225500D01*
X1221553Y682053D01*
X1205096D01*
X1203181Y683968D01*
G01X1385766Y29526D02*
Y34303D01*
X1367069Y53000D01*
X1362156D01*
X1323500Y91656D01*
Y129563D01*
X1318867Y134196D01*
Y325133D01*
X1312000Y332000D01*
Y353500D01*
X1276050Y389450D01*
Y429050D01*
X1283500Y436500D01*
Y447050D01*
X1287950Y451500D01*
Y533134D01*
X1319950Y565134D01*
Y658953D01*
X1296003Y682900D01*
X1255321D01*
X1250221Y688000D01*
X1223785D01*
X1220583Y684798D01*
X1207576D01*
X1206781Y684003D01*
G01X1235482Y546982D02*
Y537518D01*
X1235500Y537500D01*
Y503500D01*
X1224650Y492650D01*
Y444836D01*
X1227500Y441986D01*
Y434500D01*
X1249000Y413000D01*
Y391500D01*
X1291500Y349000D01*
Y87375D01*
X1316875Y62000D01*
X1335758D01*
X1349500Y48258D01*
Y45274D01*
X1362146Y32628D01*
Y29526D01*
G01X1231632Y537000D02*
X1232500Y536132D01*
Y513000D01*
X1221650Y502150D01*
Y443593D01*
X1224500Y440743D01*
Y433000D01*
X1246000Y411500D01*
Y390000D01*
X1288500Y347500D01*
Y86132D01*
X1317632Y57000D01*
X1331815D01*
X1350039Y38776D01*
X1350229D01*
X1357521Y31484D01*
Y24906D01*
X1354271Y21656D01*
G01X1240173Y550327D02*
X1238000Y548154D01*
Y502888D01*
X1226650Y491538D01*
Y445665D01*
X1229500Y442815D01*
Y435500D01*
X1251000Y414000D01*
Y392500D01*
X1293500Y350000D01*
Y337500D01*
X1299550Y331450D01*
Y286473D01*
X1295367Y282290D01*
Y86337D01*
X1304704Y77000D01*
X1323587D01*
X1351500Y49087D01*
Y46103D01*
X1365396Y32207D01*
Y24906D01*
X1362146Y21656D01*
G01X1370021D02*
X1373271Y24906D01*
Y30873D01*
X1356000Y48144D01*
Y50647D01*
X1312867Y93780D01*
Y302633D01*
X1304000Y311500D01*
Y332658D01*
X1297500Y339158D01*
Y352000D01*
X1255000Y394500D01*
Y420000D01*
X1244950Y430050D01*
Y432732D01*
X1233500Y444182D01*
Y444473D01*
X1230650Y447323D01*
Y489150D01*
X1242000Y500500D01*
Y544500D01*
X1240000Y546500D01*
G01X1370021Y29526D02*
Y30411D01*
X1354000Y46432D01*
Y49818D01*
X1297367Y106451D01*
Y281367D01*
X1301550Y285550D01*
Y332279D01*
X1295500Y338329D01*
Y350829D01*
X1253000Y393329D01*
Y415000D01*
X1231500Y436500D01*
Y443644D01*
X1228650Y446494D01*
Y490150D01*
X1240000Y501500D01*
Y542900D01*
G01X1231450Y677500D02*
X1240400D01*
X1258850Y659050D01*
X1286330D01*
X1313950Y631430D01*
Y592087D01*
X1287621Y565758D01*
X1276500D01*
X1260500Y549758D01*
Y546400D01*
G01X1316500Y839000D02*
X1312834Y842666D01*
X1241166D01*
X1225000Y826500D01*
X1223000D01*
G01X1218500Y834500D02*
Y838451D01*
X1234999Y854950D01*
X1312550D01*
X1317000Y850500D01*
G01X1318113Y846371D02*
X1230436D01*
X1229807Y847000D01*
G01X1253000Y511000D02*
Y505500D01*
X1232950Y485450D01*
Y448276D01*
X1235800Y445426D01*
Y445200D01*
X1247500Y433500D01*
Y431000D01*
X1257500Y421000D01*
Y395500D01*
X1301500Y351500D01*
Y339000D01*
X1306000Y334500D01*
G01X1237500Y675500D02*
X1239500D01*
X1259950Y655050D01*
X1265808D01*
X1267050Y656292D01*
Y656408D01*
X1267997Y657355D01*
X1285903D01*
X1312450Y630808D01*
Y595287D01*
X1306625Y589462D01*
X1305809D01*
X1295923Y579576D01*
X1272196D01*
X1255500Y562880D01*
Y504500D01*
X1235250Y484250D01*
Y449229D01*
X1238079Y446400D01*
X1238100D01*
X1250000Y434500D01*
Y433000D01*
X1260500Y422500D01*
Y396000D01*
X1306000Y350500D01*
Y338500D01*
G01X1312500Y838000D02*
X1309834Y840666D01*
X1249568D01*
X1235258Y826356D01*
Y820758D01*
G01X1257100Y664300D02*
X1264471D01*
X1266771Y662000D01*
X1278730D01*
X1280460Y663730D01*
X1282076D01*
X1283806Y662000D01*
X1286700D01*
X1291100Y657600D01*
X1309900D01*
X1311100Y656400D01*
G01X1280000Y420500D02*
X1284500Y425000D01*
Y428500D01*
X1291200Y435200D01*
Y439117D01*
X1290250Y440067D01*
Y441933D01*
X1291200Y442883D01*
Y448921D01*
X1291950Y449671D01*
Y470267D01*
X1295750Y474067D01*
Y475933D01*
X1291950Y479733D01*
Y531050D01*
X1324000Y563100D01*
Y621708D01*
X1327067Y624775D01*
Y628049D01*
X1324000Y631116D01*
Y658500D01*
X1330018Y664518D01*
X1330276D01*
X1331418Y665660D01*
Y665918D01*
X1334500Y669000D01*
G01X1310425Y660062D02*
X1308496D01*
X1305208Y663350D01*
X1303592D01*
X1303292Y663050D01*
X1289950D01*
X1286500Y666500D01*
X1280157D01*
X1279257Y665600D01*
X1266000D01*
G01X1293960Y528740D02*
Y528860D01*
X1303000Y537900D01*
Y538700D01*
X1329500Y565200D01*
Y608513D01*
X1337987Y617000D01*
X1356600D01*
X1357300Y617700D01*
G01X1304700Y536000D02*
X1305200Y536500D01*
X1317758D01*
X1331500Y550242D01*
Y605601D01*
X1335901Y610002D01*
X1347207D01*
X1347617Y610412D01*
G01X1317000Y850500D02*
X1325250Y842250D01*
Y834250D01*
G54D16*
X560829Y290355D03*
X556889Y308070D03*
X552954Y315945D03*
X576574Y290355D03*
X564764Y298230D03*
X572639Y308070D03*
X568699Y315945D03*
X592324Y290355D03*
X580514Y298230D03*
X588384Y308070D03*
X584449Y315945D03*
X608069Y290355D03*
X596259Y298230D03*
X604134Y308070D03*
X600199Y315945D03*
X612009Y298230D03*
X722244D03*
X718309Y290355D03*
X726179Y315945D03*
X730119Y308070D03*
G54D26*
G01X-185516Y-508119D02*
Y-490619D01*
G01X-176346D02*
Y-508119D01*
G01Y-499369D02*
X-185516D01*
G01X-163431Y-508119D02*
X-165178Y-507827D01*
X-166706Y-506661D01*
X-168016Y-504911D01*
X-168890Y-502869D01*
X-169326Y-500536D01*
Y-498202D01*
X-168890Y-495869D01*
X-168016Y-493827D01*
X-166706Y-492078D01*
X-165178Y-490911D01*
X-163431Y-490619D01*
X-161685Y-490911D01*
X-160156Y-492078D01*
X-158846Y-493827D01*
X-157972Y-495869D01*
X-157536Y-498202D01*
Y-500536D01*
X-157972Y-502869D01*
X-158846Y-504911D01*
X-160156Y-506661D01*
X-161685Y-507827D01*
X-163431Y-508119D01*
G01X-150953D02*
Y-490619D01*
X-140909Y-508119D01*
Y-490619D01*
G01X-124064Y-508119D02*
X-132798D01*
Y-490619D01*
X-124064D01*
G01X-127558Y-499077D02*
X-132798D01*
G01X-110931Y-508119D02*
Y-500244D01*
X-115298Y-490619D01*
G01X-106564D02*
X-110931Y-500244D01*
G01X-74185Y-498786D02*
X-73311Y-497911D01*
X-72656Y-496453D01*
X-72219Y-494410D01*
X-72656Y-492661D01*
X-73529Y-491494D01*
X-75058Y-490619D01*
X-80953D01*
Y-508119D01*
X-73748D01*
X-72219Y-506953D01*
X-71346Y-505202D01*
X-70909Y-503161D01*
X-71346Y-501119D01*
X-72656Y-499369D01*
X-74185Y-498786D01*
X-80953D01*
G01X-63890Y-508119D02*
X-58431Y-490619D01*
X-52972Y-508119D01*
G01X-54938Y-501994D02*
X-61925D01*
G01X-45734Y-508119D02*
Y-490619D01*
X-41368D01*
X-39621Y-491494D01*
X-38311Y-492661D01*
X-37219Y-494410D01*
X-36346Y-496453D01*
X-36128Y-499369D01*
X-36346Y-502286D01*
X-37219Y-504328D01*
X-38311Y-506078D01*
X-39621Y-507244D01*
X-41368Y-508119D01*
X-45734D01*
G01X-22121Y-499369D02*
X-17754D01*
Y-504619D01*
X-19064Y-506369D01*
X-20593Y-507536D01*
X-22776Y-508119D01*
X-24959Y-507536D01*
X-26488Y-506369D01*
X-27798Y-504619D01*
X-28671Y-502577D01*
X-29108Y-500244D01*
Y-498202D01*
X-28671Y-496453D01*
X-27798Y-494410D01*
X-26488Y-492661D01*
X-25178Y-491494D01*
X-23431Y-490619D01*
X-21903D01*
X-20156Y-491202D01*
X-18846Y-492369D01*
G01X-1564Y-508119D02*
X-10298D01*
Y-490619D01*
X-1564D01*
G01X-5058Y-499077D02*
X-10298D01*
G01X7202Y-508119D02*
Y-490619D01*
X12661D01*
X14407Y-491494D01*
X15499Y-492661D01*
X15936Y-494994D01*
X15499Y-497328D01*
X14189Y-498786D01*
X12661Y-499661D01*
X7202D01*
G01X12661D02*
X15936Y-508119D01*
G01X48315Y-498786D02*
X49189Y-497911D01*
X49844Y-496453D01*
X50281Y-494410D01*
X49844Y-492661D01*
X48971Y-491494D01*
X47442Y-490619D01*
X41547D01*
Y-508119D01*
X48752D01*
X50281Y-506953D01*
X51154Y-505202D01*
X51591Y-503161D01*
X51154Y-501119D01*
X49844Y-499369D01*
X48315Y-498786D01*
X41547D01*
G01X58610Y-508119D02*
X64069Y-490619D01*
X69528Y-508119D01*
G01X67562Y-501994D02*
X60575D01*
G01X76984Y-505786D02*
X78731Y-507244D01*
X80696Y-508119D01*
X82442D01*
X84189Y-507244D01*
X85499Y-505786D01*
X86154Y-503744D01*
X85717Y-501703D01*
X84626Y-499952D01*
X82661Y-498786D01*
X80041Y-498202D01*
X78512Y-497036D01*
X77857Y-494994D01*
X78294Y-492952D01*
X79386Y-491494D01*
X80914Y-490619D01*
X82442D01*
X83971Y-491202D01*
X85281Y-492661D01*
G01X103436Y-508119D02*
X94702D01*
Y-490619D01*
X103436D01*
G01X99942Y-499077D02*
X94702D01*
G01X118315Y-498786D02*
X119189Y-497911D01*
X119844Y-496453D01*
X120281Y-494410D01*
X119844Y-492661D01*
X118971Y-491494D01*
X117442Y-490619D01*
X111547D01*
Y-508119D01*
X118752D01*
X120281Y-506953D01*
X121154Y-505202D01*
X121591Y-503161D01*
X121154Y-501119D01*
X119844Y-499369D01*
X118315Y-498786D01*
X111547D01*
G01X134069Y-508119D02*
X132322Y-507827D01*
X130794Y-506661D01*
X129484Y-504911D01*
X128610Y-502869D01*
X128174Y-500536D01*
Y-498202D01*
X128610Y-495869D01*
X129484Y-493827D01*
X130794Y-492078D01*
X132322Y-490911D01*
X134069Y-490619D01*
X135815Y-490911D01*
X137344Y-492078D01*
X138654Y-493827D01*
X139528Y-495869D01*
X139964Y-498202D01*
Y-500536D01*
X139528Y-502869D01*
X138654Y-504911D01*
X137344Y-506661D01*
X135815Y-507827D01*
X134069Y-508119D01*
G01X146110D02*
X151569Y-490619D01*
X157028Y-508119D01*
G01X155062Y-501994D02*
X148075D01*
G01X164702Y-508119D02*
Y-490619D01*
X170161D01*
X171907Y-491494D01*
X172999Y-492661D01*
X173436Y-494994D01*
X172999Y-497328D01*
X171689Y-498786D01*
X170161Y-499661D01*
X164702D01*
G01X170161D02*
X173436Y-508119D01*
G01X181766D02*
Y-490619D01*
X186132D01*
X187879Y-491494D01*
X189189Y-492661D01*
X190281Y-494410D01*
X191154Y-496453D01*
X191372Y-499369D01*
X191154Y-502286D01*
X190281Y-504328D01*
X189189Y-506078D01*
X187879Y-507244D01*
X186132Y-508119D01*
X181766D01*
G01X-37858Y-463119D02*
Y-445619D01*
X-32181Y-460202D01*
X-26504Y-445619D01*
Y-463119D01*
G01X-14681D02*
X-15991Y-462827D01*
X-17301Y-461661D01*
X-18175Y-459619D01*
X-18611Y-457286D01*
X-18175Y-454952D01*
X-17301Y-452911D01*
X-15991Y-451744D01*
X-14681Y-451453D01*
X-13371Y-451744D01*
X-12061Y-452911D01*
X-11188Y-454952D01*
X-10969Y-457286D01*
X-11188Y-459619D01*
X-12061Y-461661D01*
X-13371Y-462827D01*
X-14681Y-463119D01*
G01X6749Y-445619D02*
Y-463119D01*
G01Y-460495D02*
X5876Y-461953D01*
X4565Y-462827D01*
X3037Y-463119D01*
X1291Y-462536D01*
X-19Y-461078D01*
X-893Y-459328D01*
X-1111Y-457286D01*
X-893Y-455244D01*
X-19Y-453494D01*
X1291Y-452036D01*
X3037Y-451453D01*
X4565Y-451744D01*
X5657Y-452328D01*
X6749Y-453494D01*
G01X17044Y-455244D02*
X24031D01*
X23376Y-453202D01*
X22284Y-452036D01*
X20756Y-451453D01*
X19227Y-451744D01*
X17917Y-452619D01*
X17044Y-454661D01*
X16607Y-456411D01*
Y-458161D01*
X17044Y-459911D01*
X18136Y-461661D01*
X19446Y-462827D01*
X20974Y-463119D01*
X22502Y-462536D01*
X24031Y-460786D01*
G01X37819Y-463119D02*
Y-445619D01*
G01X281019Y-508119D02*
Y-490619D01*
X278399Y-494119D01*
G01Y-508119D02*
X283639D01*
G01X293716Y-504619D02*
X295025Y-506661D01*
X296772Y-507827D01*
X298737Y-508119D01*
X300484Y-507827D01*
X302231Y-506369D01*
X303322Y-504619D01*
X303541Y-502869D01*
X303104Y-500828D01*
X301576Y-499369D01*
X300047Y-498786D01*
X298082D01*
G01X300047D02*
X301357Y-497911D01*
X302449Y-496453D01*
X302886Y-494703D01*
X302449Y-492952D01*
X301357Y-491494D01*
X299392Y-490619D01*
X297427Y-490911D01*
X295462Y-492078D01*
G01X312307Y-506078D02*
X313836Y-507536D01*
X315582Y-508119D01*
X317329Y-507536D01*
X318857Y-505786D01*
X319949Y-503161D01*
X320386Y-500536D01*
Y-497328D01*
X319949Y-494703D01*
X318857Y-492369D01*
X317547Y-491202D01*
X316019Y-490619D01*
X314272Y-491202D01*
X312962Y-492369D01*
X312089Y-494119D01*
X311652Y-496453D01*
X312089Y-498494D01*
X313181Y-500536D01*
X314491Y-501703D01*
X316019Y-501994D01*
X317765Y-501411D01*
X319076Y-499952D01*
X320386Y-497328D01*
G01X336139Y-508119D02*
Y-490619D01*
X328060Y-503161D01*
X338978D01*
G01X351019Y-508119D02*
X352547Y-507827D01*
X354294Y-506953D01*
X355386Y-505495D01*
X355822Y-503452D01*
X355386Y-501411D01*
X354076Y-499661D01*
X352111Y-498786D01*
X349927D01*
X348617Y-498202D01*
X347525Y-496744D01*
X347089Y-494703D01*
X347744Y-492661D01*
X349272Y-491202D01*
X351019Y-490619D01*
X352765Y-491202D01*
X354294Y-492661D01*
X354949Y-494703D01*
X354512Y-496744D01*
X353421Y-498202D01*
X352111Y-498786D01*
X349927D01*
X347962Y-499661D01*
X346652Y-501411D01*
X346216Y-503452D01*
X346652Y-505495D01*
X347744Y-506953D01*
X349491Y-507827D01*
X351019Y-508119D01*
G01X267902Y-463119D02*
Y-445619D01*
X273142D01*
X274889Y-446494D01*
X276199Y-448536D01*
X276636Y-450869D01*
X276199Y-453202D01*
X275107Y-454952D01*
X273142Y-455828D01*
X267902D01*
G01X294572Y-447078D02*
X293262Y-446202D01*
X291734Y-445619D01*
X289987D01*
X288022Y-446494D01*
X286494Y-447952D01*
X285402Y-449703D01*
X284529Y-452619D01*
X284310Y-455244D01*
X284747Y-457869D01*
X285402Y-459619D01*
X286712Y-461369D01*
X288241Y-462536D01*
X289769Y-463119D01*
X291297D01*
X292826Y-462536D01*
X294136Y-461661D01*
X295228Y-460495D01*
G01X309015Y-453786D02*
X309889Y-452911D01*
X310544Y-451453D01*
X310981Y-449410D01*
X310544Y-447661D01*
X309671Y-446494D01*
X308142Y-445619D01*
X302247D01*
Y-463119D01*
X309452D01*
X310981Y-461953D01*
X311854Y-460202D01*
X312291Y-458161D01*
X311854Y-456119D01*
X310544Y-454369D01*
X309015Y-453786D01*
X302247D01*
G01X318219Y-468952D02*
X331319D01*
G01X337247Y-463119D02*
Y-445619D01*
X347291Y-463119D01*
Y-445619D01*
G01X359769Y-463119D02*
X358022Y-462827D01*
X356494Y-461661D01*
X355184Y-459911D01*
X354310Y-457869D01*
X353874Y-455536D01*
Y-453202D01*
X354310Y-450869D01*
X355184Y-448827D01*
X356494Y-447078D01*
X358022Y-445911D01*
X359769Y-445619D01*
X361515Y-445911D01*
X363044Y-447078D01*
X364354Y-448827D01*
X365228Y-450869D01*
X365664Y-453202D01*
Y-455536D01*
X365228Y-457869D01*
X364354Y-459911D01*
X363044Y-461661D01*
X361515Y-462827D01*
X359769Y-463119D01*
G01X410610Y-445619D02*
X416069Y-463119D01*
X421528Y-445619D01*
G01X437936Y-463119D02*
X429202D01*
Y-445619D01*
X437936D01*
G01X434442Y-454077D02*
X429202D01*
G01X446702Y-463119D02*
Y-445619D01*
X452161D01*
X453907Y-446494D01*
X454999Y-447661D01*
X455436Y-449994D01*
X454999Y-452328D01*
X453689Y-453786D01*
X452161Y-454661D01*
X446702D01*
G01X452161D02*
X455436Y-463119D01*
G01X468569Y-463702D02*
X468132Y-463411D01*
Y-462827D01*
X468569Y-462536D01*
X469006Y-462827D01*
Y-463411D01*
X468569Y-463702D01*
G01X433569Y-508119D02*
Y-490619D01*
X430949Y-494119D01*
G01Y-508119D02*
X436189D01*
G01X452815Y-498786D02*
X453689Y-497911D01*
X454344Y-496453D01*
X454781Y-494410D01*
X454344Y-492661D01*
X453471Y-491494D01*
X451942Y-490619D01*
X446047D01*
Y-508119D01*
X453252D01*
X454781Y-506953D01*
X455654Y-505202D01*
X456091Y-503161D01*
X455654Y-501119D01*
X454344Y-499369D01*
X452815Y-498786D01*
X446047D01*
G01X544152Y-445619D02*
Y-463119D01*
X552886D01*
G01X569949D02*
Y-451453D01*
G01Y-453494D02*
X569076Y-452328D01*
X567765Y-451744D01*
X566237Y-451453D01*
X564709Y-452036D01*
X563399Y-453202D01*
X562525Y-454952D01*
X562089Y-457286D01*
X562525Y-459619D01*
X563399Y-461369D01*
X564709Y-462536D01*
X566237Y-463119D01*
X567765Y-462827D01*
X569076Y-461953D01*
X569949Y-460786D01*
G01X578934Y-468369D02*
X580244Y-468952D01*
X581991Y-468369D01*
X583082Y-467203D01*
X583956Y-465744D01*
X585265Y-461078D01*
X588104Y-451453D01*
G01X581117D02*
X585265Y-461078D01*
G01X597744Y-455244D02*
X604731D01*
X604076Y-453202D01*
X602984Y-452036D01*
X601456Y-451453D01*
X599927Y-451744D01*
X598617Y-452619D01*
X597744Y-454661D01*
X597307Y-456411D01*
Y-458161D01*
X597744Y-459911D01*
X598836Y-461661D01*
X600146Y-462827D01*
X601674Y-463119D01*
X603202Y-462536D01*
X604731Y-460786D01*
G01X615462Y-463119D02*
Y-451453D01*
G01Y-453786D02*
X616554Y-452619D01*
X617646Y-451744D01*
X619174Y-451453D01*
X620265Y-451744D01*
X621576Y-452619D01*
G01X596636Y-490619D02*
Y-508119D01*
X587902D01*
G01X578917Y-500828D02*
X577389Y-498786D01*
X576079Y-497619D01*
X574332Y-497036D01*
X572804Y-497619D01*
X571712Y-498786D01*
X570839Y-500536D01*
X570621Y-502577D01*
X570839Y-504328D01*
X571712Y-506078D01*
X573023Y-507536D01*
X574551Y-508119D01*
X576297Y-507536D01*
X577826Y-505786D01*
X578699Y-503161D01*
X578917Y-500244D01*
X578481Y-496453D01*
X577826Y-494410D01*
X576734Y-492369D01*
X575206Y-490911D01*
X573677Y-490619D01*
X572149Y-491202D01*
X571057Y-492661D01*
G01X686702Y-490619D02*
Y-508119D01*
X695436D01*
G01X703984Y-513369D02*
X705294Y-513952D01*
X707041Y-513369D01*
X708132Y-512203D01*
X709006Y-510744D01*
X710315Y-506078D01*
X713154Y-496453D01*
G01X706167D02*
X710315Y-506078D01*
G01X722357Y-508119D02*
Y-496453D01*
G01Y-499369D02*
X723231Y-497911D01*
X724541Y-496744D01*
X726287Y-496453D01*
X727815Y-496744D01*
X729126Y-497911D01*
X729781Y-499952D01*
Y-508119D01*
G01X739857D02*
Y-496453D01*
G01Y-499369D02*
X740731Y-497911D01*
X742041Y-496744D01*
X743787Y-496453D01*
X745315Y-496744D01*
X746626Y-497911D01*
X747281Y-499952D01*
Y-508119D01*
G01X774202Y-490619D02*
Y-508119D01*
X782936D01*
G01X796069Y-496453D02*
Y-508119D01*
G01Y-491786D02*
X795632Y-491494D01*
Y-490911D01*
X796069Y-490619D01*
X796506Y-490911D01*
Y-491494D01*
X796069Y-491786D01*
G01X809857Y-496453D02*
Y-504619D01*
X810731Y-506661D01*
X812041Y-507827D01*
X813569Y-508119D01*
X815097Y-507827D01*
X816407Y-506661D01*
X817281Y-504619D01*
G01Y-508119D02*
Y-496453D01*
G01X686266Y-463119D02*
Y-445619D01*
X690632D01*
X692379Y-446494D01*
X693689Y-447661D01*
X694781Y-449410D01*
X695654Y-451453D01*
X695872Y-454369D01*
X695654Y-457286D01*
X694781Y-459328D01*
X693689Y-461078D01*
X692379Y-462244D01*
X690632Y-463119D01*
X686266D01*
G01X705294Y-455244D02*
X712281D01*
X711626Y-453202D01*
X710534Y-452036D01*
X709006Y-451453D01*
X707477Y-451744D01*
X706167Y-452619D01*
X705294Y-454661D01*
X704857Y-456411D01*
Y-458161D01*
X705294Y-459911D01*
X706386Y-461661D01*
X707696Y-462827D01*
X709224Y-463119D01*
X710752Y-462536D01*
X712281Y-460786D01*
G01X722794Y-461078D02*
X723886Y-462244D01*
X725414Y-463119D01*
X726724D01*
X728034Y-462536D01*
X728907Y-461661D01*
X729344Y-460495D01*
X729126Y-458744D01*
X728252Y-457869D01*
X724322Y-456119D01*
X723449Y-454077D01*
X723886Y-452619D01*
X724759Y-451744D01*
X726069Y-451453D01*
X727379Y-451744D01*
X728689Y-452619D01*
G01X743569Y-451453D02*
Y-463119D01*
G01Y-446786D02*
X743132Y-446494D01*
Y-445911D01*
X743569Y-445619D01*
X744006Y-445911D01*
Y-446494D01*
X743569Y-446786D01*
G01X758012Y-467494D02*
X759541Y-468661D01*
X761287Y-468952D01*
X762815Y-468661D01*
X764126Y-467203D01*
X764999Y-465161D01*
Y-451453D01*
G01Y-453786D02*
X764126Y-452619D01*
X762815Y-451744D01*
X761287Y-451453D01*
X759541Y-452036D01*
X758449Y-453202D01*
X757575Y-455244D01*
X757139Y-457286D01*
X757357Y-459036D01*
X758231Y-461078D01*
X759541Y-462536D01*
X761287Y-463119D01*
X762597Y-462827D01*
X764126Y-461661D01*
X764999Y-460495D01*
G01X774857Y-463119D02*
Y-451453D01*
G01Y-454369D02*
X775731Y-452911D01*
X777041Y-451744D01*
X778787Y-451453D01*
X780315Y-451744D01*
X781626Y-452911D01*
X782281Y-454952D01*
Y-463119D01*
G01X792794Y-455244D02*
X799781D01*
X799126Y-453202D01*
X798034Y-452036D01*
X796506Y-451453D01*
X794977Y-451744D01*
X793667Y-452619D01*
X792794Y-454661D01*
X792357Y-456411D01*
Y-458161D01*
X792794Y-459911D01*
X793886Y-461661D01*
X795196Y-462827D01*
X796724Y-463119D01*
X798252Y-462536D01*
X799781Y-460786D01*
G01X810512Y-463119D02*
Y-451453D01*
G01Y-453786D02*
X811604Y-452619D01*
X812696Y-451744D01*
X814224Y-451453D01*
X815315Y-451744D01*
X816626Y-452619D01*
G01X857269Y-508119D02*
Y-490619D01*
X854649Y-494119D01*
G01Y-508119D02*
X859889D01*
G01X874769D02*
Y-490619D01*
X872149Y-494119D01*
G01Y-508119D02*
X877389D01*
G01X888339Y-508702D02*
X896199Y-490619D01*
G01X909769Y-508119D02*
Y-490619D01*
X907149Y-494119D01*
G01Y-508119D02*
X912389D01*
G01X922466Y-504619D02*
X923775Y-506661D01*
X925522Y-507827D01*
X927487Y-508119D01*
X929234Y-507827D01*
X930981Y-506369D01*
X932072Y-504619D01*
X932291Y-502869D01*
X931854Y-500828D01*
X930326Y-499369D01*
X928797Y-498786D01*
X926832D01*
G01X928797D02*
X930107Y-497911D01*
X931199Y-496453D01*
X931636Y-494703D01*
X931199Y-492952D01*
X930107Y-491494D01*
X928142Y-490619D01*
X926177Y-490911D01*
X924212Y-492078D01*
G01X940839Y-508702D02*
X948699Y-490619D01*
G01X958121Y-493536D02*
X959431Y-491786D01*
X960959Y-490911D01*
X962706Y-490619D01*
X964889Y-491202D01*
X966417Y-492661D01*
X966854Y-494410D01*
X966636Y-496161D01*
X965762Y-497619D01*
X961396Y-500536D01*
X959431Y-502577D01*
X958121Y-505495D01*
X957684Y-508119D01*
X966854D01*
G01X979769Y-490619D02*
X978022Y-491202D01*
X976712Y-492661D01*
X975839Y-494410D01*
X975184Y-496744D01*
X974966Y-499369D01*
X975184Y-501994D01*
X975839Y-504328D01*
X976712Y-506078D01*
X978022Y-507536D01*
X979769Y-508119D01*
X981515Y-507536D01*
X982826Y-506078D01*
X983699Y-504328D01*
X984354Y-501994D01*
X984572Y-499369D01*
X984354Y-496744D01*
X983699Y-494410D01*
X982826Y-492661D01*
X981515Y-491202D01*
X979769Y-490619D01*
G01X997269Y-508119D02*
Y-490619D01*
X994649Y-494119D01*
G01Y-508119D02*
X999889D01*
G01X1017389D02*
Y-490619D01*
X1009310Y-503161D01*
X1020228D01*
G01X904966Y-463119D02*
Y-445619D01*
X909332D01*
X911079Y-446494D01*
X912389Y-447661D01*
X913481Y-449410D01*
X914354Y-451453D01*
X914572Y-454369D01*
X914354Y-457286D01*
X913481Y-459328D01*
X912389Y-461078D01*
X911079Y-462244D01*
X909332Y-463119D01*
X904966D01*
G01X931199D02*
Y-451453D01*
G01Y-453494D02*
X930326Y-452328D01*
X929015Y-451744D01*
X927487Y-451453D01*
X925959Y-452036D01*
X924649Y-453202D01*
X923775Y-454952D01*
X923339Y-457286D01*
X923775Y-459619D01*
X924649Y-461369D01*
X925959Y-462536D01*
X927487Y-463119D01*
X929015Y-462827D01*
X930326Y-461953D01*
X931199Y-460786D01*
G01X944769Y-445619D02*
Y-463119D01*
G01X941712Y-451453D02*
X947826D01*
G01X958994Y-455244D02*
X965981D01*
X965326Y-453202D01*
X964234Y-452036D01*
X962706Y-451453D01*
X961177Y-451744D01*
X959867Y-452619D01*
X958994Y-454661D01*
X958557Y-456411D01*
Y-458161D01*
X958994Y-459911D01*
X960086Y-461661D01*
X961396Y-462827D01*
X962924Y-463119D01*
X964452Y-462536D01*
X965981Y-460786D01*
G54D17*
X585315Y44134D03*
X654527D03*
G54D27*
G01X368600Y134646D02*
X366800D01*
G01X368800Y144105D02*
X367100D01*
G01X368333Y148827D02*
G03X366708Y149500I-1625J-1625D01*
G01X365106D01*
G02X362808Y150452I0J3250D01*
G01X360574Y152686D01*
X360187D01*
X360126Y152747D01*
G01X368329Y151956D02*
X366922Y150549D01*
G02X366200Y150250I-722J722D01*
G01X365107D01*
G02X363339Y150982I0J2500D01*
G01X361107Y153214D01*
Y153605D01*
X361046Y153666D01*
G01X1167048Y714312D02*
Y714548D01*
X1168624Y716124D01*
Y718439D01*
X1169698Y719513D01*
G54D18*
X1084646Y43267D03*
G54D19*
X1346396Y21656D03*
Y29526D03*
X1362146Y21656D03*
X1354271D03*
X1362146Y29526D03*
X1354271D03*
X1377896Y21656D03*
X1370021D03*
X1377896Y29526D03*
X1370021D03*
X1385766Y21656D03*
Y29526D03*
M02*
